FILE_TYPE = MACRO_DRAWING;
SET COLOR_WIRE YELLOW;
SET COLOR_PROP ORANGE;
SET COLOR_DOT WHITE;
SET COLOR_ARC YELLOW;
SET COLOR_BODY GREEN;
SET COLOR_NOTE PURPLE;
SET PROP_DISPLAY VALUE;
SET PAGE_NUMBER P82;
FORCEADD TAP..1
(-650 4200);
FORCEPROP 3 LASTPIN (-700 4200) SIG_NAME M_A_CPU0_SA_DQ<29>
J 0
(-690 4210);
DISPLAY 0.659574 (-690 4210);
PAINT MONO (-690 4210);
DISPLAY INVISIBLE (-690 4210);
FORCEPROP 1 LASTPIN (-700 4200) BN 29
J 0
(-712 4208);
DISPLAY 0.680851 (-712 4208);
PAINT GREEN (-712 4208);
FORCEPROP 2 LAST CDS_LIB standard
J 0
(-650 4200);
DISPLAY INVISIBLE (-650 4200);
FORCEPROP 1 LAST BODY_TYPE PLUMBING
J 0
(-650 4250);
DISPLAY 0.872340 (-650 4250);
PAINT GREEN (-650 4250);
DISPLAY INVISIBLE (-650 4250);
FORCEPROP 1 LAST HDL_TAP TRUE
J 0
(-325 4075);
DISPLAY 0.872340 (-325 4075);
DISPLAY INVISIBLE (-325 4075);
FORCEPROP 1 LAST PATH I10
J 0
(-652 4200);
DISPLAY 0.872340 (-652 4200);
PAINT GREEN (-652 4200);
DISPLAY INVISIBLE (-652 4200);
FORCEADD OFFPAGE..2
(3325 4275);
FORCEPROP 2 LAST $XR1 83 
J 0
(3604 4275);
DISPLAY 0.638298 (3604 4275);
PAINT MONO (3604 4275);
FORCEPROP 2 LAST $XR0 20 
J 0
(3514 4275);
DISPLAY 0.638298 (3514 4275);
PAINT MONO (3514 4275);
FORCEPROP 2 LAST CDS_LIB standard
J 0
(3325 4275);
PAINT MONO (3325 4275);
DISPLAY INVISIBLE (3325 4275);
FORCEPROP 1 LAST OFFPAGE TRUE
J 0
(3650 4150);
DISPLAY 1.170213 (3650 4150);
PAINT GREEN (3650 4150);
DISPLAY INVISIBLE (3650 4150);
FORCEPROP 1 LAST COMMENT_BODY TRUE
J 0
(3280 4180);
DISPLAY 1.170213 (3280 4180);
PAINT GREEN (3280 4180);
DISPLAY INVISIBLE (3280 4180);
FORCEPROP 2 LAST PATH I100
J 0
(3500 4350);
DISPLAY 1.021277 (3500 4350);
DISPLAY INVISIBLE (3500 4350);
FORCEADD OFFPAGE..2
(3325 4325);
FORCEPROP 2 LAST $XR1 83 
J 0
(3604 4325);
DISPLAY 0.638298 (3604 4325);
PAINT MONO (3604 4325);
FORCEPROP 2 LAST $XR0 20 
J 0
(3514 4325);
DISPLAY 0.638298 (3514 4325);
PAINT MONO (3514 4325);
FORCEPROP 2 LAST CDS_LIB standard
J 0
(3325 4325);
PAINT MONO (3325 4325);
DISPLAY INVISIBLE (3325 4325);
FORCEPROP 1 LAST OFFPAGE TRUE
J 0
(3650 4200);
DISPLAY 1.170213 (3650 4200);
PAINT GREEN (3650 4200);
DISPLAY INVISIBLE (3650 4200);
FORCEPROP 1 LAST COMMENT_BODY TRUE
J 0
(3280 4230);
DISPLAY 1.170213 (3280 4230);
PAINT GREEN (3280 4230);
DISPLAY INVISIBLE (3280 4230);
FORCEPROP 2 LAST PATH I101
J 0
(3500 4400);
DISPLAY 1.021277 (3500 4400);
DISPLAY INVISIBLE (3500 4400);
FORCEADD OFFPAGE..2
(3325 3275);
FORCEPROP 2 LAST $XR1 83 
J 0
(3604 3275);
DISPLAY 0.638298 (3604 3275);
PAINT MONO (3604 3275);
FORCEPROP 2 LAST $XR0 20 
J 0
(3514 3275);
DISPLAY 0.638298 (3514 3275);
PAINT MONO (3514 3275);
FORCEPROP 2 LAST CDS_LIB standard
J 0
(3325 3275);
PAINT MONO (3325 3275);
DISPLAY INVISIBLE (3325 3275);
FORCEPROP 1 LAST OFFPAGE TRUE
J 0
(3650 3150);
DISPLAY 1.170213 (3650 3150);
PAINT GREEN (3650 3150);
DISPLAY INVISIBLE (3650 3150);
FORCEPROP 1 LAST COMMENT_BODY TRUE
J 0
(3280 3180);
DISPLAY 1.170213 (3280 3180);
PAINT GREEN (3280 3180);
DISPLAY INVISIBLE (3280 3180);
FORCEPROP 2 LAST PATH I102
J 0
(3500 3350);
DISPLAY 1.021277 (3500 3350);
DISPLAY INVISIBLE (3500 3350);
FORCEADD OFFPAGE..2
(3325 3225);
FORCEPROP 2 LAST $XR1 83 
J 0
(3604 3225);
DISPLAY 0.638298 (3604 3225);
PAINT MONO (3604 3225);
FORCEPROP 2 LAST $XR0 20 
J 0
(3514 3225);
DISPLAY 0.638298 (3514 3225);
PAINT MONO (3514 3225);
FORCEPROP 2 LAST CDS_LIB standard
J 0
(3325 3225);
PAINT MONO (3325 3225);
DISPLAY INVISIBLE (3325 3225);
FORCEPROP 1 LAST OFFPAGE TRUE
J 0
(3650 3100);
DISPLAY 1.170213 (3650 3100);
PAINT GREEN (3650 3100);
DISPLAY INVISIBLE (3650 3100);
FORCEPROP 1 LAST COMMENT_BODY TRUE
J 0
(3280 3130);
DISPLAY 1.170213 (3280 3130);
PAINT GREEN (3280 3130);
DISPLAY INVISIBLE (3280 3130);
FORCEPROP 2 LAST PATH I103
J 0
(3500 3300);
DISPLAY 1.021277 (3500 3300);
DISPLAY INVISIBLE (3500 3300);
FORCEADD TAP..1
(2375 3200);
FORCEPROP 3 LASTPIN (2325 3200) SIG_NAME M_A_CPU0_SB_DQS_DN<9>
J 0
(2335 3210);
DISPLAY 0.659574 (2335 3210);
PAINT MONO (2335 3210);
DISPLAY INVISIBLE (2335 3210);
FORCEPROP 1 LASTPIN (2325 3200) BN 9
J 0
(2313 3208);
DISPLAY 0.680851 (2313 3208);
PAINT GREEN (2313 3208);
FORCEPROP 2 LAST CDS_LIB standard
J 0
(2375 3200);
DISPLAY INVISIBLE (2375 3200);
FORCEPROP 1 LAST BODY_TYPE PLUMBING
J 0
(2375 3250);
DISPLAY 0.872340 (2375 3250);
PAINT GREEN (2375 3250);
DISPLAY INVISIBLE (2375 3250);
FORCEPROP 1 LAST HDL_TAP TRUE
J 0
(2700 3075);
DISPLAY 0.872340 (2700 3075);
DISPLAY INVISIBLE (2700 3075);
FORCEPROP 1 LAST PATH I104
J 0
(2373 3200);
DISPLAY 0.872340 (2373 3200);
PAINT GREEN (2373 3200);
DISPLAY INVISIBLE (2373 3200);
FORCEADD TAP..1
(2375 3100);
FORCEPROP 3 LASTPIN (2325 3100) SIG_NAME M_A_CPU0_SB_DQS_DN<8>
J 0
(2335 3110);
DISPLAY 0.659574 (2335 3110);
PAINT MONO (2335 3110);
DISPLAY INVISIBLE (2335 3110);
FORCEPROP 1 LASTPIN (2325 3100) BN 8
J 0
(2313 3108);
DISPLAY 0.680851 (2313 3108);
PAINT GREEN (2313 3108);
FORCEPROP 2 LAST CDS_LIB standard
J 0
(2375 3100);
DISPLAY INVISIBLE (2375 3100);
FORCEPROP 1 LAST BODY_TYPE PLUMBING
J 0
(2375 3150);
DISPLAY 0.872340 (2375 3150);
PAINT GREEN (2375 3150);
DISPLAY INVISIBLE (2375 3150);
FORCEPROP 1 LAST HDL_TAP TRUE
J 0
(2700 2975);
DISPLAY 0.872340 (2700 2975);
DISPLAY INVISIBLE (2700 2975);
FORCEPROP 1 LAST PATH I105
J 0
(2373 3100);
DISPLAY 0.872340 (2373 3100);
PAINT GREEN (2373 3100);
DISPLAY INVISIBLE (2373 3100);
FORCEADD TAP..1
(2200 3250);
FORCEPROP 3 LASTPIN (2150 3250) SIG_NAME M_A_CPU0_SB_DQS_DP<9>
J 0
(2160 3260);
DISPLAY 0.659574 (2160 3260);
PAINT MONO (2160 3260);
DISPLAY INVISIBLE (2160 3260);
FORCEPROP 1 LASTPIN (2150 3250) BN 9
J 0
(2138 3258);
DISPLAY 0.680851 (2138 3258);
PAINT GREEN (2138 3258);
FORCEPROP 2 LAST CDS_LIB standard
J 0
(2200 3250);
DISPLAY INVISIBLE (2200 3250);
FORCEPROP 1 LAST BODY_TYPE PLUMBING
J 0
(2200 3300);
DISPLAY 0.872340 (2200 3300);
PAINT GREEN (2200 3300);
DISPLAY INVISIBLE (2200 3300);
FORCEPROP 1 LAST HDL_TAP TRUE
J 0
(2525 3125);
DISPLAY 0.872340 (2525 3125);
DISPLAY INVISIBLE (2525 3125);
FORCEPROP 1 LAST PATH I106
J 0
(2198 3250);
DISPLAY 0.872340 (2198 3250);
PAINT GREEN (2198 3250);
DISPLAY INVISIBLE (2198 3250);
FORCEADD TAP..1
(2200 3050);
FORCEPROP 3 LASTPIN (2150 3050) SIG_NAME M_A_CPU0_SB_DQS_DP<7>
J 0
(2160 3060);
DISPLAY 0.659574 (2160 3060);
PAINT MONO (2160 3060);
DISPLAY INVISIBLE (2160 3060);
FORCEPROP 1 LASTPIN (2150 3050) BN 7
J 0
(2138 3058);
DISPLAY 0.680851 (2138 3058);
PAINT GREEN (2138 3058);
FORCEPROP 2 LAST CDS_LIB standard
J 0
(2200 3050);
DISPLAY INVISIBLE (2200 3050);
FORCEPROP 1 LAST BODY_TYPE PLUMBING
J 0
(2200 3100);
DISPLAY 0.872340 (2200 3100);
PAINT GREEN (2200 3100);
DISPLAY INVISIBLE (2200 3100);
FORCEPROP 1 LAST HDL_TAP TRUE
J 0
(2525 2925);
DISPLAY 0.872340 (2525 2925);
DISPLAY INVISIBLE (2525 2925);
FORCEPROP 1 LAST PATH I107
J 0
(2198 3050);
DISPLAY 0.872340 (2198 3050);
PAINT GREEN (2198 3050);
DISPLAY INVISIBLE (2198 3050);
FORCEADD TAP..1
(2200 3150);
FORCEPROP 3 LASTPIN (2150 3150) SIG_NAME M_A_CPU0_SB_DQS_DP<8>
J 0
(2160 3160);
DISPLAY 0.659574 (2160 3160);
PAINT MONO (2160 3160);
DISPLAY INVISIBLE (2160 3160);
FORCEPROP 1 LASTPIN (2150 3150) BN 8
J 0
(2138 3158);
DISPLAY 0.680851 (2138 3158);
PAINT GREEN (2138 3158);
FORCEPROP 2 LAST CDS_LIB standard
J 0
(2200 3150);
DISPLAY INVISIBLE (2200 3150);
FORCEPROP 1 LAST BODY_TYPE PLUMBING
J 0
(2200 3200);
DISPLAY 0.872340 (2200 3200);
PAINT GREEN (2200 3200);
DISPLAY INVISIBLE (2200 3200);
FORCEPROP 1 LAST HDL_TAP TRUE
J 0
(2525 3025);
DISPLAY 0.872340 (2525 3025);
DISPLAY INVISIBLE (2525 3025);
FORCEPROP 1 LAST PATH I108
J 0
(2198 3150);
DISPLAY 0.872340 (2198 3150);
PAINT GREEN (2198 3150);
DISPLAY INVISIBLE (2198 3150);
FORCEADD TAP..1
(2375 3000);
FORCEPROP 3 LASTPIN (2325 3000) SIG_NAME M_A_CPU0_SB_DQS_DN<7>
J 0
(2335 3010);
DISPLAY 0.659574 (2335 3010);
PAINT MONO (2335 3010);
DISPLAY INVISIBLE (2335 3010);
FORCEPROP 1 LASTPIN (2325 3000) BN 7
J 0
(2313 3008);
DISPLAY 0.680851 (2313 3008);
PAINT GREEN (2313 3008);
FORCEPROP 2 LAST CDS_LIB standard
J 0
(2375 3000);
DISPLAY INVISIBLE (2375 3000);
FORCEPROP 1 LAST BODY_TYPE PLUMBING
J 0
(2375 3050);
DISPLAY 0.872340 (2375 3050);
PAINT GREEN (2375 3050);
DISPLAY INVISIBLE (2375 3050);
FORCEPROP 1 LAST HDL_TAP TRUE
J 0
(2700 2875);
DISPLAY 0.872340 (2700 2875);
DISPLAY INVISIBLE (2700 2875);
FORCEPROP 1 LAST PATH I109
J 0
(2373 3000);
DISPLAY 0.872340 (2373 3000);
PAINT GREEN (2373 3000);
DISPLAY INVISIBLE (2373 3000);
FORCEADD TAP..1
(-650 4250);
FORCEPROP 3 LASTPIN (-700 4250) SIG_NAME M_A_CPU0_SA_DQ<30>
J 0
(-690 4260);
DISPLAY 0.659574 (-690 4260);
PAINT MONO (-690 4260);
DISPLAY INVISIBLE (-690 4260);
FORCEPROP 1 LASTPIN (-700 4250) BN 30
J 0
(-712 4258);
DISPLAY 0.680851 (-712 4258);
PAINT GREEN (-712 4258);
FORCEPROP 2 LAST CDS_LIB standard
J 0
(-650 4250);
DISPLAY INVISIBLE (-650 4250);
FORCEPROP 1 LAST BODY_TYPE PLUMBING
J 0
(-650 4300);
DISPLAY 0.872340 (-650 4300);
PAINT GREEN (-650 4300);
DISPLAY INVISIBLE (-650 4300);
FORCEPROP 1 LAST HDL_TAP TRUE
J 0
(-325 4125);
DISPLAY 0.872340 (-325 4125);
DISPLAY INVISIBLE (-325 4125);
FORCEPROP 1 LAST PATH I11
J 0
(-652 4250);
DISPLAY 0.872340 (-652 4250);
PAINT GREEN (-652 4250);
DISPLAY INVISIBLE (-652 4250);
FORCEADD TAP..1
(2375 2900);
FORCEPROP 3 LASTPIN (2325 2900) SIG_NAME M_A_CPU0_SB_DQS_DN<6>
J 0
(2335 2910);
DISPLAY 0.659574 (2335 2910);
PAINT MONO (2335 2910);
DISPLAY INVISIBLE (2335 2910);
FORCEPROP 1 LASTPIN (2325 2900) BN 6
J 0
(2313 2908);
DISPLAY 0.680851 (2313 2908);
PAINT GREEN (2313 2908);
FORCEPROP 2 LAST CDS_LIB standard
J 0
(2375 2900);
DISPLAY INVISIBLE (2375 2900);
FORCEPROP 1 LAST BODY_TYPE PLUMBING
J 0
(2375 2950);
DISPLAY 0.872340 (2375 2950);
PAINT GREEN (2375 2950);
DISPLAY INVISIBLE (2375 2950);
FORCEPROP 1 LAST HDL_TAP TRUE
J 0
(2700 2775);
DISPLAY 0.872340 (2700 2775);
DISPLAY INVISIBLE (2700 2775);
FORCEPROP 1 LAST PATH I110
J 0
(2373 2900);
DISPLAY 0.872340 (2373 2900);
PAINT GREEN (2373 2900);
DISPLAY INVISIBLE (2373 2900);
FORCEADD TAP..1
(2375 2800);
FORCEPROP 3 LASTPIN (2325 2800) SIG_NAME M_A_CPU0_SB_DQS_DN<5>
J 0
(2335 2810);
DISPLAY 0.659574 (2335 2810);
PAINT MONO (2335 2810);
DISPLAY INVISIBLE (2335 2810);
FORCEPROP 1 LASTPIN (2325 2800) BN 5
J 0
(2313 2808);
DISPLAY 0.680851 (2313 2808);
PAINT GREEN (2313 2808);
FORCEPROP 2 LAST CDS_LIB standard
J 0
(2375 2800);
DISPLAY INVISIBLE (2375 2800);
FORCEPROP 1 LAST BODY_TYPE PLUMBING
J 0
(2375 2850);
DISPLAY 0.872340 (2375 2850);
PAINT GREEN (2375 2850);
DISPLAY INVISIBLE (2375 2850);
FORCEPROP 1 LAST HDL_TAP TRUE
J 0
(2700 2675);
DISPLAY 0.872340 (2700 2675);
DISPLAY INVISIBLE (2700 2675);
FORCEPROP 1 LAST PATH I111
J 0
(2373 2800);
DISPLAY 0.872340 (2373 2800);
PAINT GREEN (2373 2800);
DISPLAY INVISIBLE (2373 2800);
FORCEADD TAP..1
(2375 2700);
FORCEPROP 3 LASTPIN (2325 2700) SIG_NAME M_A_CPU0_SB_DQS_DN<4>
J 0
(2335 2710);
DISPLAY 0.659574 (2335 2710);
PAINT MONO (2335 2710);
DISPLAY INVISIBLE (2335 2710);
FORCEPROP 1 LASTPIN (2325 2700) BN 4
J 0
(2313 2708);
DISPLAY 0.680851 (2313 2708);
PAINT GREEN (2313 2708);
FORCEPROP 2 LAST CDS_LIB standard
J 0
(2375 2700);
PAINT MONO (2375 2700);
DISPLAY INVISIBLE (2375 2700);
FORCEPROP 1 LAST BODY_TYPE PLUMBING
J 0
(2375 2750);
DISPLAY 0.872340 (2375 2750);
PAINT GREEN (2375 2750);
DISPLAY INVISIBLE (2375 2750);
FORCEPROP 1 LAST HDL_TAP TRUE
J 0
(2700 2575);
DISPLAY 0.872340 (2700 2575);
DISPLAY INVISIBLE (2700 2575);
FORCEPROP 1 LAST PATH I112
J 0
(2373 2700);
DISPLAY 0.872340 (2373 2700);
PAINT GREEN (2373 2700);
DISPLAY INVISIBLE (2373 2700);
FORCEADD TAP..1
(2375 2600);
FORCEPROP 3 LASTPIN (2325 2600) SIG_NAME M_A_CPU0_SB_DQS_DN<3>
J 0
(2335 2610);
DISPLAY 0.659574 (2335 2610);
PAINT MONO (2335 2610);
DISPLAY INVISIBLE (2335 2610);
FORCEPROP 1 LASTPIN (2325 2600) BN 3
J 0
(2313 2608);
DISPLAY 0.680851 (2313 2608);
PAINT GREEN (2313 2608);
FORCEPROP 2 LAST CDS_LIB standard
J 0
(2375 2600);
PAINT MONO (2375 2600);
DISPLAY INVISIBLE (2375 2600);
FORCEPROP 1 LAST BODY_TYPE PLUMBING
J 0
(2375 2650);
DISPLAY 0.872340 (2375 2650);
PAINT GREEN (2375 2650);
DISPLAY INVISIBLE (2375 2650);
FORCEPROP 1 LAST HDL_TAP TRUE
J 0
(2700 2475);
DISPLAY 0.872340 (2700 2475);
DISPLAY INVISIBLE (2700 2475);
FORCEPROP 1 LAST PATH I113
J 0
(2373 2600);
DISPLAY 0.872340 (2373 2600);
PAINT GREEN (2373 2600);
DISPLAY INVISIBLE (2373 2600);
FORCEADD TAP..1
(2375 2500);
FORCEPROP 3 LASTPIN (2325 2500) SIG_NAME M_A_CPU0_SB_DQS_DN<2>
J 0
(2335 2510);
DISPLAY 0.659574 (2335 2510);
PAINT MONO (2335 2510);
DISPLAY INVISIBLE (2335 2510);
FORCEPROP 1 LASTPIN (2325 2500) BN 2
J 0
(2313 2508);
DISPLAY 0.680851 (2313 2508);
PAINT GREEN (2313 2508);
FORCEPROP 2 LAST CDS_LIB standard
J 0
(2375 2500);
DISPLAY INVISIBLE (2375 2500);
FORCEPROP 1 LAST BODY_TYPE PLUMBING
J 0
(2375 2550);
DISPLAY 0.872340 (2375 2550);
PAINT GREEN (2375 2550);
DISPLAY INVISIBLE (2375 2550);
FORCEPROP 1 LAST HDL_TAP TRUE
J 0
(2700 2375);
DISPLAY 0.872340 (2700 2375);
DISPLAY INVISIBLE (2700 2375);
FORCEPROP 1 LAST PATH I114
J 0
(2373 2500);
DISPLAY 0.872340 (2373 2500);
PAINT GREEN (2373 2500);
DISPLAY INVISIBLE (2373 2500);
FORCEADD TAP..1
(2375 2300);
FORCEPROP 3 LASTPIN (2325 2300) SIG_NAME M_A_CPU0_SB_DQS_DN<0>
J 0
(2335 2310);
DISPLAY 0.659574 (2335 2310);
PAINT MONO (2335 2310);
DISPLAY INVISIBLE (2335 2310);
FORCEPROP 1 LASTPIN (2325 2300) BN 0
J 0
(2313 2308);
DISPLAY 0.680851 (2313 2308);
PAINT GREEN (2313 2308);
FORCEPROP 2 LAST CDS_LIB standard
J 0
(2375 2300);
PAINT MONO (2375 2300);
DISPLAY INVISIBLE (2375 2300);
FORCEPROP 1 LAST BODY_TYPE PLUMBING
J 0
(2375 2350);
DISPLAY 0.872340 (2375 2350);
PAINT GREEN (2375 2350);
DISPLAY INVISIBLE (2375 2350);
FORCEPROP 1 LAST HDL_TAP TRUE
J 0
(2700 2175);
DISPLAY 0.872340 (2700 2175);
DISPLAY INVISIBLE (2700 2175);
FORCEPROP 1 LAST PATH I115
J 0
(2373 2300);
DISPLAY 0.872340 (2373 2300);
PAINT GREEN (2373 2300);
DISPLAY INVISIBLE (2373 2300);
FORCEADD TAP..1
(2375 2400);
FORCEPROP 3 LASTPIN (2325 2400) SIG_NAME M_A_CPU0_SB_DQS_DN<1>
J 0
(2335 2410);
DISPLAY 0.659574 (2335 2410);
PAINT MONO (2335 2410);
DISPLAY INVISIBLE (2335 2410);
FORCEPROP 1 LASTPIN (2325 2400) BN 1
J 0
(2313 2408);
DISPLAY 0.680851 (2313 2408);
PAINT GREEN (2313 2408);
FORCEPROP 2 LAST CDS_LIB standard
J 0
(2375 2400);
DISPLAY INVISIBLE (2375 2400);
FORCEPROP 1 LAST BODY_TYPE PLUMBING
J 0
(2375 2450);
DISPLAY 0.872340 (2375 2450);
PAINT GREEN (2375 2450);
DISPLAY INVISIBLE (2375 2450);
FORCEPROP 1 LAST HDL_TAP TRUE
J 0
(2700 2275);
DISPLAY 0.872340 (2700 2275);
DISPLAY INVISIBLE (2700 2275);
FORCEPROP 1 LAST PATH I116
J 0
(2373 2400);
DISPLAY 0.872340 (2373 2400);
PAINT GREEN (2373 2400);
DISPLAY INVISIBLE (2373 2400);
FORCEADD TAP..1
(2200 2950);
FORCEPROP 3 LASTPIN (2150 2950) SIG_NAME M_A_CPU0_SB_DQS_DP<6>
J 0
(2160 2960);
DISPLAY 0.659574 (2160 2960);
PAINT MONO (2160 2960);
DISPLAY INVISIBLE (2160 2960);
FORCEPROP 1 LASTPIN (2150 2950) BN 6
J 0
(2138 2958);
DISPLAY 0.680851 (2138 2958);
PAINT GREEN (2138 2958);
FORCEPROP 2 LAST CDS_LIB standard
J 0
(2200 2950);
DISPLAY INVISIBLE (2200 2950);
FORCEPROP 1 LAST BODY_TYPE PLUMBING
J 0
(2200 3000);
DISPLAY 0.872340 (2200 3000);
PAINT GREEN (2200 3000);
DISPLAY INVISIBLE (2200 3000);
FORCEPROP 1 LAST HDL_TAP TRUE
J 0
(2525 2825);
DISPLAY 0.872340 (2525 2825);
DISPLAY INVISIBLE (2525 2825);
FORCEPROP 1 LAST PATH I117
J 0
(2198 2950);
DISPLAY 0.872340 (2198 2950);
PAINT GREEN (2198 2950);
DISPLAY INVISIBLE (2198 2950);
FORCEADD TAP..1
(2200 2850);
FORCEPROP 3 LASTPIN (2150 2850) SIG_NAME M_A_CPU0_SB_DQS_DP<5>
J 0
(2160 2860);
DISPLAY 0.659574 (2160 2860);
PAINT MONO (2160 2860);
DISPLAY INVISIBLE (2160 2860);
FORCEPROP 1 LASTPIN (2150 2850) BN 5
J 0
(2138 2858);
DISPLAY 0.680851 (2138 2858);
PAINT GREEN (2138 2858);
FORCEPROP 2 LAST CDS_LIB standard
J 0
(2200 2850);
DISPLAY INVISIBLE (2200 2850);
FORCEPROP 1 LAST BODY_TYPE PLUMBING
J 0
(2200 2900);
DISPLAY 0.872340 (2200 2900);
PAINT GREEN (2200 2900);
DISPLAY INVISIBLE (2200 2900);
FORCEPROP 1 LAST HDL_TAP TRUE
J 0
(2525 2725);
DISPLAY 0.872340 (2525 2725);
DISPLAY INVISIBLE (2525 2725);
FORCEPROP 1 LAST PATH I118
J 0
(2198 2850);
DISPLAY 0.872340 (2198 2850);
PAINT GREEN (2198 2850);
DISPLAY INVISIBLE (2198 2850);
FORCEADD TAP..1
(2200 2750);
FORCEPROP 3 LASTPIN (2150 2750) SIG_NAME M_A_CPU0_SB_DQS_DP<4>
J 0
(2160 2760);
DISPLAY 0.659574 (2160 2760);
PAINT MONO (2160 2760);
DISPLAY INVISIBLE (2160 2760);
FORCEPROP 1 LASTPIN (2150 2750) BN 4
J 0
(2138 2758);
DISPLAY 0.680851 (2138 2758);
PAINT GREEN (2138 2758);
FORCEPROP 2 LAST CDS_LIB standard
J 0
(2200 2750);
PAINT MONO (2200 2750);
DISPLAY INVISIBLE (2200 2750);
FORCEPROP 1 LAST BODY_TYPE PLUMBING
J 0
(2200 2800);
DISPLAY 0.872340 (2200 2800);
PAINT GREEN (2200 2800);
DISPLAY INVISIBLE (2200 2800);
FORCEPROP 1 LAST HDL_TAP TRUE
J 0
(2525 2625);
DISPLAY 0.872340 (2525 2625);
DISPLAY INVISIBLE (2525 2625);
FORCEPROP 1 LAST PATH I119
J 0
(2198 2750);
DISPLAY 0.872340 (2198 2750);
PAINT GREEN (2198 2750);
DISPLAY INVISIBLE (2198 2750);
FORCEADD TAP..1
(-650 4300);
FORCEPROP 3 LASTPIN (-700 4300) SIG_NAME M_A_CPU0_SA_DQ<31>
J 0
(-690 4310);
DISPLAY 0.659574 (-690 4310);
PAINT MONO (-690 4310);
DISPLAY INVISIBLE (-690 4310);
FORCEPROP 1 LASTPIN (-700 4300) BN 31
J 0
(-712 4308);
DISPLAY 0.680851 (-712 4308);
PAINT GREEN (-712 4308);
FORCEPROP 2 LAST CDS_LIB standard
J 0
(-650 4300);
DISPLAY INVISIBLE (-650 4300);
FORCEPROP 1 LAST BODY_TYPE PLUMBING
J 0
(-650 4350);
DISPLAY 0.872340 (-650 4350);
PAINT GREEN (-650 4350);
DISPLAY INVISIBLE (-650 4350);
FORCEPROP 1 LAST HDL_TAP TRUE
J 0
(-325 4175);
DISPLAY 0.872340 (-325 4175);
DISPLAY INVISIBLE (-325 4175);
FORCEPROP 1 LAST PATH I12
J 0
(-652 4300);
DISPLAY 0.872340 (-652 4300);
PAINT GREEN (-652 4300);
DISPLAY INVISIBLE (-652 4300);
FORCEADD TAP..1
(2200 2550);
FORCEPROP 3 LASTPIN (2150 2550) SIG_NAME M_A_CPU0_SB_DQS_DP<2>
J 0
(2160 2560);
DISPLAY 0.659574 (2160 2560);
PAINT MONO (2160 2560);
DISPLAY INVISIBLE (2160 2560);
FORCEPROP 1 LASTPIN (2150 2550) BN 2
J 0
(2138 2558);
DISPLAY 0.680851 (2138 2558);
PAINT GREEN (2138 2558);
FORCEPROP 2 LAST CDS_LIB standard
J 0
(2200 2550);
DISPLAY INVISIBLE (2200 2550);
FORCEPROP 1 LAST BODY_TYPE PLUMBING
J 0
(2200 2600);
DISPLAY 0.872340 (2200 2600);
PAINT GREEN (2200 2600);
DISPLAY INVISIBLE (2200 2600);
FORCEPROP 1 LAST HDL_TAP TRUE
J 0
(2525 2425);
DISPLAY 0.872340 (2525 2425);
DISPLAY INVISIBLE (2525 2425);
FORCEPROP 1 LAST PATH I120
J 0
(2198 2550);
DISPLAY 0.872340 (2198 2550);
PAINT GREEN (2198 2550);
DISPLAY INVISIBLE (2198 2550);
FORCEADD TAP..1
(2200 2650);
FORCEPROP 3 LASTPIN (2150 2650) SIG_NAME M_A_CPU0_SB_DQS_DP<3>
J 0
(2160 2660);
DISPLAY 0.659574 (2160 2660);
PAINT MONO (2160 2660);
DISPLAY INVISIBLE (2160 2660);
FORCEPROP 1 LASTPIN (2150 2650) BN 3
J 0
(2138 2658);
DISPLAY 0.680851 (2138 2658);
PAINT GREEN (2138 2658);
FORCEPROP 2 LAST CDS_LIB standard
J 0
(2200 2650);
PAINT MONO (2200 2650);
DISPLAY INVISIBLE (2200 2650);
FORCEPROP 1 LAST BODY_TYPE PLUMBING
J 0
(2200 2700);
DISPLAY 0.872340 (2200 2700);
PAINT GREEN (2200 2700);
DISPLAY INVISIBLE (2200 2700);
FORCEPROP 1 LAST HDL_TAP TRUE
J 0
(2525 2525);
DISPLAY 0.872340 (2525 2525);
DISPLAY INVISIBLE (2525 2525);
FORCEPROP 1 LAST PATH I121
J 0
(2198 2650);
DISPLAY 0.872340 (2198 2650);
PAINT GREEN (2198 2650);
DISPLAY INVISIBLE (2198 2650);
FORCEADD TAP..1
(2200 2450);
FORCEPROP 3 LASTPIN (2150 2450) SIG_NAME M_A_CPU0_SB_DQS_DP<1>
J 0
(2160 2460);
DISPLAY 0.659574 (2160 2460);
PAINT MONO (2160 2460);
DISPLAY INVISIBLE (2160 2460);
FORCEPROP 1 LASTPIN (2150 2450) BN 1
J 0
(2138 2458);
DISPLAY 0.680851 (2138 2458);
PAINT GREEN (2138 2458);
FORCEPROP 2 LAST CDS_LIB standard
J 0
(2200 2450);
DISPLAY INVISIBLE (2200 2450);
FORCEPROP 1 LAST BODY_TYPE PLUMBING
J 0
(2200 2500);
DISPLAY 0.872340 (2200 2500);
PAINT GREEN (2200 2500);
DISPLAY INVISIBLE (2200 2500);
FORCEPROP 1 LAST HDL_TAP TRUE
J 0
(2525 2325);
DISPLAY 0.872340 (2525 2325);
DISPLAY INVISIBLE (2525 2325);
FORCEPROP 1 LAST PATH I122
J 0
(2198 2450);
DISPLAY 0.872340 (2198 2450);
PAINT GREEN (2198 2450);
DISPLAY INVISIBLE (2198 2450);
FORCEADD TAP..1
(2200 2350);
FORCEPROP 3 LASTPIN (2150 2350) SIG_NAME M_A_CPU0_SB_DQS_DP<0>
J 0
(2160 2360);
DISPLAY 0.659574 (2160 2360);
PAINT MONO (2160 2360);
DISPLAY INVISIBLE (2160 2360);
FORCEPROP 1 LASTPIN (2150 2350) BN 0
J 0
(2138 2358);
DISPLAY 0.680851 (2138 2358);
PAINT GREEN (2138 2358);
FORCEPROP 2 LAST CDS_LIB standard
J 0
(2200 2350);
PAINT MONO (2200 2350);
DISPLAY INVISIBLE (2200 2350);
FORCEPROP 1 LAST BODY_TYPE PLUMBING
J 0
(2200 2400);
DISPLAY 0.872340 (2200 2400);
PAINT GREEN (2200 2400);
DISPLAY INVISIBLE (2200 2400);
FORCEPROP 1 LAST HDL_TAP TRUE
J 0
(2525 2225);
DISPLAY 0.872340 (2525 2225);
DISPLAY INVISIBLE (2525 2225);
FORCEPROP 1 LAST PATH I123
J 0
(2198 2350);
DISPLAY 0.872340 (2198 2350);
PAINT GREEN (2198 2350);
DISPLAY INVISIBLE (2198 2350);
FORCEADD TAP..1
R 2
(-2300 4000);
FORCEPROP 3 LASTPIN (-2250 4000) SIG_NAME M_A_CPU0_SA_CA<0>
J 0
(-2240 4010);
DISPLAY 0.659574 (-2240 4010);
PAINT MONO (-2240 4010);
DISPLAY INVISIBLE (-2240 4010);
FORCEPROP 1 LASTPIN (-2250 4000) BN 0
J 2
(-2238 4008);
DISPLAY 0.680851 (-2238 4008);
PAINT GREEN (-2238 4008);
FORCEPROP 2 LAST CDS_LIB standard
J 0
(-2300 4000);
DISPLAY INVISIBLE (-2300 4000);
FORCEPROP 1 LAST BODY_TYPE PLUMBING
J 2
(-2300 4050);
DISPLAY 0.872340 (-2300 4050);
PAINT GREEN (-2300 4050);
DISPLAY INVISIBLE (-2300 4050);
FORCEPROP 1 LAST HDL_TAP TRUE
J 2
(-2625 3875);
DISPLAY 0.872340 (-2625 3875);
DISPLAY INVISIBLE (-2625 3875);
FORCEPROP 1 LAST PATH I124
J 2
(-2298 4000);
DISPLAY 0.872340 (-2298 4000);
PAINT GREEN (-2298 4000);
DISPLAY INVISIBLE (-2298 4000);
FORCEADD TAP..1
R 2
(-2300 4050);
FORCEPROP 3 LASTPIN (-2250 4050) SIG_NAME M_A_CPU0_SA_CA<1>
J 0
(-2240 4060);
DISPLAY 0.659574 (-2240 4060);
PAINT MONO (-2240 4060);
DISPLAY INVISIBLE (-2240 4060);
FORCEPROP 1 LASTPIN (-2250 4050) BN 1
J 2
(-2238 4058);
DISPLAY 0.680851 (-2238 4058);
PAINT GREEN (-2238 4058);
FORCEPROP 2 LAST CDS_LIB standard
J 0
(-2300 4050);
DISPLAY INVISIBLE (-2300 4050);
FORCEPROP 1 LAST BODY_TYPE PLUMBING
J 2
(-2300 4100);
DISPLAY 0.872340 (-2300 4100);
PAINT GREEN (-2300 4100);
DISPLAY INVISIBLE (-2300 4100);
FORCEPROP 1 LAST HDL_TAP TRUE
J 2
(-2625 3925);
DISPLAY 0.872340 (-2625 3925);
DISPLAY INVISIBLE (-2625 3925);
FORCEPROP 1 LAST PATH I125
J 2
(-2298 4050);
DISPLAY 0.872340 (-2298 4050);
PAINT GREEN (-2298 4050);
DISPLAY INVISIBLE (-2298 4050);
FORCEADD TAP..1
R 2
(-2300 4100);
FORCEPROP 3 LASTPIN (-2250 4100) SIG_NAME M_A_CPU0_SA_CA<2>
J 0
(-2240 4110);
DISPLAY 0.659574 (-2240 4110);
PAINT MONO (-2240 4110);
DISPLAY INVISIBLE (-2240 4110);
FORCEPROP 1 LASTPIN (-2250 4100) BN 2
J 2
(-2238 4108);
DISPLAY 0.680851 (-2238 4108);
PAINT GREEN (-2238 4108);
FORCEPROP 2 LAST CDS_LIB standard
J 0
(-2300 4100);
DISPLAY INVISIBLE (-2300 4100);
FORCEPROP 1 LAST BODY_TYPE PLUMBING
J 2
(-2300 4150);
DISPLAY 0.872340 (-2300 4150);
PAINT GREEN (-2300 4150);
DISPLAY INVISIBLE (-2300 4150);
FORCEPROP 1 LAST HDL_TAP TRUE
J 2
(-2625 3975);
DISPLAY 0.872340 (-2625 3975);
DISPLAY INVISIBLE (-2625 3975);
FORCEPROP 1 LAST PATH I126
J 2
(-2298 4100);
DISPLAY 0.872340 (-2298 4100);
PAINT GREEN (-2298 4100);
DISPLAY INVISIBLE (-2298 4100);
FORCEADD TAP..1
R 2
(-2300 4200);
FORCEPROP 3 LASTPIN (-2250 4200) SIG_NAME M_A_CPU0_SA_CA<4>
J 0
(-2240 4210);
DISPLAY 0.659574 (-2240 4210);
PAINT MONO (-2240 4210);
DISPLAY INVISIBLE (-2240 4210);
FORCEPROP 1 LASTPIN (-2250 4200) BN 4
J 2
(-2238 4208);
DISPLAY 0.680851 (-2238 4208);
PAINT GREEN (-2238 4208);
FORCEPROP 2 LAST CDS_LIB standard
J 0
(-2300 4200);
DISPLAY INVISIBLE (-2300 4200);
FORCEPROP 1 LAST BODY_TYPE PLUMBING
J 2
(-2300 4250);
DISPLAY 0.872340 (-2300 4250);
PAINT GREEN (-2300 4250);
DISPLAY INVISIBLE (-2300 4250);
FORCEPROP 1 LAST HDL_TAP TRUE
J 2
(-2625 4075);
DISPLAY 0.872340 (-2625 4075);
DISPLAY INVISIBLE (-2625 4075);
FORCEPROP 1 LAST PATH I128
J 2
(-2298 4200);
DISPLAY 0.872340 (-2298 4200);
PAINT GREEN (-2298 4200);
DISPLAY INVISIBLE (-2298 4200);
FORCEADD TAP..1
R 2
(-2300 4150);
FORCEPROP 3 LASTPIN (-2250 4150) SIG_NAME M_A_CPU0_SA_CA<3>
J 0
(-2240 4160);
DISPLAY 0.659574 (-2240 4160);
PAINT MONO (-2240 4160);
DISPLAY INVISIBLE (-2240 4160);
FORCEPROP 1 LASTPIN (-2250 4150) BN 3
J 2
(-2238 4158);
DISPLAY 0.680851 (-2238 4158);
PAINT GREEN (-2238 4158);
FORCEPROP 2 LAST CDS_LIB standard
J 0
(-2300 4150);
DISPLAY INVISIBLE (-2300 4150);
FORCEPROP 1 LAST BODY_TYPE PLUMBING
J 2
(-2300 4200);
DISPLAY 0.872340 (-2300 4200);
PAINT GREEN (-2300 4200);
DISPLAY INVISIBLE (-2300 4200);
FORCEPROP 1 LAST HDL_TAP TRUE
J 2
(-2625 4025);
DISPLAY 0.872340 (-2625 4025);
DISPLAY INVISIBLE (-2625 4025);
FORCEPROP 1 LAST PATH I129
J 2
(-2298 4150);
DISPLAY 0.872340 (-2298 4150);
PAINT GREEN (-2298 4150);
DISPLAY INVISIBLE (-2298 4150);
FORCEADD TAP..1
(-650 4150);
FORCEPROP 3 LASTPIN (-700 4150) SIG_NAME M_A_CPU0_SA_DQ<28>
J 0
(-690 4160);
DISPLAY 0.659574 (-690 4160);
PAINT MONO (-690 4160);
DISPLAY INVISIBLE (-690 4160);
FORCEPROP 1 LASTPIN (-700 4150) BN 28
J 0
(-712 4158);
DISPLAY 0.680851 (-712 4158);
PAINT GREEN (-712 4158);
FORCEPROP 2 LAST CDS_LIB standard
J 0
(-650 4150);
DISPLAY INVISIBLE (-650 4150);
FORCEPROP 1 LAST BODY_TYPE PLUMBING
J 0
(-650 4200);
DISPLAY 0.872340 (-650 4200);
PAINT GREEN (-650 4200);
DISPLAY INVISIBLE (-650 4200);
FORCEPROP 1 LAST HDL_TAP TRUE
J 0
(-325 4025);
DISPLAY 0.872340 (-325 4025);
DISPLAY INVISIBLE (-325 4025);
FORCEPROP 1 LAST PATH I13
J 0
(-652 4150);
DISPLAY 0.872340 (-652 4150);
PAINT GREEN (-652 4150);
DISPLAY INVISIBLE (-652 4150);
FORCEADD TAP..1
R 2
(-2300 4250);
FORCEPROP 3 LASTPIN (-2250 4250) SIG_NAME M_A_CPU0_SA_CA<5>
J 0
(-2240 4260);
DISPLAY 0.659574 (-2240 4260);
PAINT MONO (-2240 4260);
DISPLAY INVISIBLE (-2240 4260);
FORCEPROP 1 LASTPIN (-2250 4250) BN 5
J 2
(-2238 4258);
DISPLAY 0.680851 (-2238 4258);
PAINT GREEN (-2238 4258);
FORCEPROP 2 LAST CDS_LIB standard
J 0
(-2300 4250);
DISPLAY INVISIBLE (-2300 4250);
FORCEPROP 1 LAST BODY_TYPE PLUMBING
J 2
(-2300 4300);
DISPLAY 0.872340 (-2300 4300);
PAINT GREEN (-2300 4300);
DISPLAY INVISIBLE (-2300 4300);
FORCEPROP 1 LAST HDL_TAP TRUE
J 2
(-2625 4125);
DISPLAY 0.872340 (-2625 4125);
DISPLAY INVISIBLE (-2625 4125);
FORCEPROP 1 LAST PATH I130
J 2
(-2298 4250);
DISPLAY 0.872340 (-2298 4250);
PAINT GREEN (-2298 4250);
DISPLAY INVISIBLE (-2298 4250);
FORCEADD TAP..1
R 2
(-2300 4300);
FORCEPROP 3 LASTPIN (-2250 4300) SIG_NAME M_A_CPU0_SA_CA<6>
J 0
(-2240 4310);
DISPLAY 0.659574 (-2240 4310);
PAINT MONO (-2240 4310);
DISPLAY INVISIBLE (-2240 4310);
FORCEPROP 1 LASTPIN (-2250 4300) BN 6
J 2
(-2238 4308);
DISPLAY 0.680851 (-2238 4308);
PAINT GREEN (-2238 4308);
FORCEPROP 2 LAST CDS_LIB standard
J 0
(-2300 4300);
DISPLAY INVISIBLE (-2300 4300);
FORCEPROP 1 LAST BODY_TYPE PLUMBING
J 2
(-2300 4350);
DISPLAY 0.872340 (-2300 4350);
PAINT GREEN (-2300 4350);
DISPLAY INVISIBLE (-2300 4350);
FORCEPROP 1 LAST HDL_TAP TRUE
J 2
(-2625 4175);
DISPLAY 0.872340 (-2625 4175);
DISPLAY INVISIBLE (-2625 4175);
FORCEPROP 1 LAST PATH I131
J 2
(-2298 4300);
DISPLAY 0.872340 (-2298 4300);
PAINT GREEN (-2298 4300);
DISPLAY INVISIBLE (-2298 4300);
FORCEADD OFFPAGE..1
(-3225 4325);
FORCEPROP 2 LAST $XR1 83 
J 0
(-3536 4325);
DISPLAY 0.638298 (-3536 4325);
PAINT MONO (-3536 4325);
FORCEPROP 2 LAST $XR0 20 
J 0
(-3446 4325);
DISPLAY 0.638298 (-3446 4325);
PAINT MONO (-3446 4325);
FORCEPROP 2 LAST CDS_LIB standard
J 0
(-3225 4325);
PAINT MONO (-3225 4325);
DISPLAY INVISIBLE (-3225 4325);
FORCEPROP 1 LAST OFFPAGE TRUE
J 0
(-2900 4200);
DISPLAY 0.872340 (-2900 4200);
DISPLAY INVISIBLE (-2900 4200);
FORCEPROP 1 LAST COMMENT_BODY TRUE
J 0
(-3100 4225);
DISPLAY 0.872340 (-3100 4225);
PAINT GREEN (-3100 4225);
DISPLAY INVISIBLE (-3100 4225);
FORCEPROP 2 LAST PATH I132
J 0
(-3175 4400);
DISPLAY 1.021277 (-3175 4400);
DISPLAY INVISIBLE (-3175 4400);
FORCEADD TAP..1
R 2
(-2300 3600);
FORCEPROP 3 LASTPIN (-2250 3600) SIG_NAME M_A_CPU0_SB_CA<0>
J 0
(-2240 3610);
DISPLAY 0.659574 (-2240 3610);
PAINT MONO (-2240 3610);
DISPLAY INVISIBLE (-2240 3610);
FORCEPROP 1 LASTPIN (-2250 3600) BN 0
J 2
(-2238 3608);
DISPLAY 0.680851 (-2238 3608);
PAINT GREEN (-2238 3608);
FORCEPROP 2 LAST CDS_LIB standard
J 0
(-2300 3600);
DISPLAY INVISIBLE (-2300 3600);
FORCEPROP 1 LAST BODY_TYPE PLUMBING
J 2
(-2300 3650);
DISPLAY 0.872340 (-2300 3650);
PAINT GREEN (-2300 3650);
DISPLAY INVISIBLE (-2300 3650);
FORCEPROP 1 LAST HDL_TAP TRUE
J 2
(-2625 3475);
DISPLAY 0.872340 (-2625 3475);
DISPLAY INVISIBLE (-2625 3475);
FORCEPROP 1 LAST PATH I133
J 2
(-2298 3600);
DISPLAY 0.872340 (-2298 3600);
PAINT GREEN (-2298 3600);
DISPLAY INVISIBLE (-2298 3600);
FORCEADD TAP..1
R 2
(-2300 3900);
FORCEPROP 3 LASTPIN (-2250 3900) SIG_NAME M_A_CPU0_SB_CA<6>
J 0
(-2240 3910);
DISPLAY 0.659574 (-2240 3910);
PAINT MONO (-2240 3910);
DISPLAY INVISIBLE (-2240 3910);
FORCEPROP 1 LASTPIN (-2250 3900) BN 6
J 2
(-2238 3908);
DISPLAY 0.680851 (-2238 3908);
PAINT GREEN (-2238 3908);
FORCEPROP 2 LAST CDS_LIB standard
J 0
(-2300 3900);
DISPLAY INVISIBLE (-2300 3900);
FORCEPROP 1 LAST BODY_TYPE PLUMBING
J 2
(-2300 3950);
DISPLAY 0.872340 (-2300 3950);
PAINT GREEN (-2300 3950);
DISPLAY INVISIBLE (-2300 3950);
FORCEPROP 1 LAST HDL_TAP TRUE
J 2
(-2625 3775);
DISPLAY 0.872340 (-2625 3775);
DISPLAY INVISIBLE (-2625 3775);
FORCEPROP 1 LAST PATH I134
J 2
(-2298 3900);
DISPLAY 0.872340 (-2298 3900);
PAINT GREEN (-2298 3900);
DISPLAY INVISIBLE (-2298 3900);
FORCEADD TAP..1
R 2
(-2300 3850);
FORCEPROP 3 LASTPIN (-2250 3850) SIG_NAME M_A_CPU0_SB_CA<5>
J 0
(-2240 3860);
DISPLAY 0.659574 (-2240 3860);
PAINT MONO (-2240 3860);
DISPLAY INVISIBLE (-2240 3860);
FORCEPROP 1 LASTPIN (-2250 3850) BN 5
J 2
(-2238 3858);
DISPLAY 0.680851 (-2238 3858);
PAINT GREEN (-2238 3858);
FORCEPROP 2 LAST CDS_LIB standard
J 0
(-2300 3850);
DISPLAY INVISIBLE (-2300 3850);
FORCEPROP 1 LAST BODY_TYPE PLUMBING
J 2
(-2300 3900);
DISPLAY 0.872340 (-2300 3900);
PAINT GREEN (-2300 3900);
DISPLAY INVISIBLE (-2300 3900);
FORCEPROP 1 LAST HDL_TAP TRUE
J 2
(-2625 3725);
DISPLAY 0.872340 (-2625 3725);
DISPLAY INVISIBLE (-2625 3725);
FORCEPROP 1 LAST PATH I135
J 2
(-2298 3850);
DISPLAY 0.872340 (-2298 3850);
PAINT GREEN (-2298 3850);
DISPLAY INVISIBLE (-2298 3850);
FORCEADD TAP..1
R 2
(-2300 3800);
FORCEPROP 3 LASTPIN (-2250 3800) SIG_NAME M_A_CPU0_SB_CA<4>
J 0
(-2240 3810);
DISPLAY 0.659574 (-2240 3810);
PAINT MONO (-2240 3810);
DISPLAY INVISIBLE (-2240 3810);
FORCEPROP 1 LASTPIN (-2250 3800) BN 4
J 2
(-2238 3808);
DISPLAY 0.680851 (-2238 3808);
PAINT GREEN (-2238 3808);
FORCEPROP 2 LAST CDS_LIB standard
J 0
(-2300 3800);
DISPLAY INVISIBLE (-2300 3800);
FORCEPROP 1 LAST BODY_TYPE PLUMBING
J 2
(-2300 3850);
DISPLAY 0.872340 (-2300 3850);
PAINT GREEN (-2300 3850);
DISPLAY INVISIBLE (-2300 3850);
FORCEPROP 1 LAST HDL_TAP TRUE
J 2
(-2625 3675);
DISPLAY 0.872340 (-2625 3675);
DISPLAY INVISIBLE (-2625 3675);
FORCEPROP 1 LAST PATH I136
J 2
(-2298 3800);
DISPLAY 0.872340 (-2298 3800);
PAINT GREEN (-2298 3800);
DISPLAY INVISIBLE (-2298 3800);
FORCEADD TAP..1
R 2
(-2300 3750);
FORCEPROP 3 LASTPIN (-2250 3750) SIG_NAME M_A_CPU0_SB_CA<3>
J 0
(-2240 3760);
DISPLAY 0.659574 (-2240 3760);
PAINT MONO (-2240 3760);
DISPLAY INVISIBLE (-2240 3760);
FORCEPROP 1 LASTPIN (-2250 3750) BN 3
J 2
(-2238 3758);
DISPLAY 0.680851 (-2238 3758);
PAINT GREEN (-2238 3758);
FORCEPROP 2 LAST CDS_LIB standard
J 0
(-2300 3750);
DISPLAY INVISIBLE (-2300 3750);
FORCEPROP 1 LAST BODY_TYPE PLUMBING
J 2
(-2300 3800);
DISPLAY 0.872340 (-2300 3800);
PAINT GREEN (-2300 3800);
DISPLAY INVISIBLE (-2300 3800);
FORCEPROP 1 LAST HDL_TAP TRUE
J 2
(-2625 3625);
DISPLAY 0.872340 (-2625 3625);
DISPLAY INVISIBLE (-2625 3625);
FORCEPROP 1 LAST PATH I137
J 2
(-2298 3750);
DISPLAY 0.872340 (-2298 3750);
PAINT GREEN (-2298 3750);
DISPLAY INVISIBLE (-2298 3750);
FORCEADD TAP..1
R 2
(-2300 3700);
FORCEPROP 3 LASTPIN (-2250 3700) SIG_NAME M_A_CPU0_SB_CA<2>
J 0
(-2240 3710);
DISPLAY 0.659574 (-2240 3710);
PAINT MONO (-2240 3710);
DISPLAY INVISIBLE (-2240 3710);
FORCEPROP 1 LASTPIN (-2250 3700) BN 2
J 2
(-2238 3708);
DISPLAY 0.680851 (-2238 3708);
PAINT GREEN (-2238 3708);
FORCEPROP 2 LAST CDS_LIB standard
J 0
(-2300 3700);
DISPLAY INVISIBLE (-2300 3700);
FORCEPROP 1 LAST BODY_TYPE PLUMBING
J 2
(-2300 3750);
DISPLAY 0.872340 (-2300 3750);
PAINT GREEN (-2300 3750);
DISPLAY INVISIBLE (-2300 3750);
FORCEPROP 1 LAST HDL_TAP TRUE
J 2
(-2625 3575);
DISPLAY 0.872340 (-2625 3575);
DISPLAY INVISIBLE (-2625 3575);
FORCEPROP 1 LAST PATH I138
J 2
(-2298 3700);
DISPLAY 0.872340 (-2298 3700);
PAINT GREEN (-2298 3700);
DISPLAY INVISIBLE (-2298 3700);
FORCEADD OFFPAGE..1
(-3225 3925);
FORCEPROP 2 LAST $XR1 83 
J 0
(-3536 3925);
DISPLAY 0.638298 (-3536 3925);
PAINT MONO (-3536 3925);
FORCEPROP 2 LAST $XR0 20 
J 0
(-3446 3925);
DISPLAY 0.638298 (-3446 3925);
PAINT MONO (-3446 3925);
FORCEPROP 2 LAST CDS_LIB standard
J 0
(-3225 3925);
PAINT MONO (-3225 3925);
DISPLAY INVISIBLE (-3225 3925);
FORCEPROP 1 LAST OFFPAGE TRUE
J 0
(-2900 3800);
DISPLAY 0.872340 (-2900 3800);
DISPLAY INVISIBLE (-2900 3800);
FORCEPROP 1 LAST COMMENT_BODY TRUE
J 0
(-3100 3825);
DISPLAY 0.872340 (-3100 3825);
PAINT GREEN (-3100 3825);
DISPLAY INVISIBLE (-3100 3825);
FORCEPROP 2 LAST PATH I139
J 0
(-3175 4000);
DISPLAY 1.021277 (-3175 4000);
DISPLAY INVISIBLE (-3175 4000);
FORCEADD OFFPAGE..3
(175 4325);
FORCEPROP 2 LAST $XR1 83 
J 0
(479 4325);
DISPLAY 0.638298 (479 4325);
PAINT MONO (479 4325);
FORCEPROP 2 LAST $XR0 20 
J 0
(389 4325);
DISPLAY 0.638298 (389 4325);
PAINT MONO (389 4325);
FORCEPROP 2 LAST CDS_LIB standard
J 2
(175 4325);
DISPLAY INVISIBLE (175 4325);
FORCEPROP 1 LAST OFFPAGE TRUE
J 0
(500 4200);
DISPLAY 0.872340 (500 4200);
DISPLAY INVISIBLE (500 4200);
FORCEPROP 1 LAST COMMENT_BODY TRUE
J 0
(125 4225);
DISPLAY 0.872340 (125 4225);
PAINT GREEN (125 4225);
DISPLAY INVISIBLE (125 4225);
FORCEPROP 2 LAST PATH I14
J 0
(375 4400);
DISPLAY 1.021277 (375 4400);
DISPLAY INVISIBLE (375 4400);
FORCEADD TAP..1
R 2
(-2300 3650);
FORCEPROP 3 LASTPIN (-2250 3650) SIG_NAME M_A_CPU0_SB_CA<1>
J 0
(-2240 3660);
DISPLAY 0.659574 (-2240 3660);
PAINT MONO (-2240 3660);
DISPLAY INVISIBLE (-2240 3660);
FORCEPROP 1 LASTPIN (-2250 3650) BN 1
J 2
(-2238 3658);
DISPLAY 0.680851 (-2238 3658);
PAINT GREEN (-2238 3658);
FORCEPROP 2 LAST CDS_LIB standard
J 0
(-2300 3650);
DISPLAY INVISIBLE (-2300 3650);
FORCEPROP 1 LAST BODY_TYPE PLUMBING
J 2
(-2300 3700);
DISPLAY 0.872340 (-2300 3700);
PAINT GREEN (-2300 3700);
DISPLAY INVISIBLE (-2300 3700);
FORCEPROP 1 LAST HDL_TAP TRUE
J 2
(-2625 3525);
DISPLAY 0.872340 (-2625 3525);
DISPLAY INVISIBLE (-2625 3525);
FORCEPROP 1 LAST PATH I140
J 2
(-2298 3650);
DISPLAY 0.872340 (-2298 3650);
PAINT GREEN (-2298 3650);
DISPLAY INVISIBLE (-2298 3650);
FORCEADD OFFPAGE..1
(-3225 3500);
FORCEPROP 2 LAST $XR1 83 
J 0
(-3536 3500);
DISPLAY 0.638298 (-3536 3500);
PAINT MONO (-3536 3500);
FORCEPROP 2 LAST $XR0 20 
J 0
(-3446 3500);
DISPLAY 0.638298 (-3446 3500);
PAINT MONO (-3446 3500);
FORCEPROP 2 LAST CDS_LIB standard
J 0
(-3225 3500);
PAINT MONO (-3225 3500);
DISPLAY INVISIBLE (-3225 3500);
FORCEPROP 1 LAST OFFPAGE TRUE
J 0
(-2900 3375);
DISPLAY 0.872340 (-2900 3375);
DISPLAY INVISIBLE (-2900 3375);
FORCEPROP 1 LAST COMMENT_BODY TRUE
J 0
(-3100 3400);
DISPLAY 0.872340 (-3100 3400);
PAINT GREEN (-3100 3400);
DISPLAY INVISIBLE (-3100 3400);
FORCEPROP 2 LAST PATH I142
J 0
(-3175 3575);
DISPLAY 1.021277 (-3175 3575);
DISPLAY INVISIBLE (-3175 3575);
FORCEADD OFFPAGE..1
(-3225 3450);
FORCEPROP 2 LAST $XR1 83 
J 0
(-3536 3450);
DISPLAY 0.638298 (-3536 3450);
PAINT MONO (-3536 3450);
FORCEPROP 2 LAST $XR0 20 
J 0
(-3446 3450);
DISPLAY 0.638298 (-3446 3450);
PAINT MONO (-3446 3450);
FORCEPROP 2 LAST CDS_LIB standard
J 0
(-3225 3450);
PAINT MONO (-3225 3450);
DISPLAY INVISIBLE (-3225 3450);
FORCEPROP 1 LAST OFFPAGE TRUE
J 0
(-2900 3325);
DISPLAY 0.872340 (-2900 3325);
DISPLAY INVISIBLE (-2900 3325);
FORCEPROP 1 LAST COMMENT_BODY TRUE
J 0
(-3100 3350);
DISPLAY 0.872340 (-3100 3350);
PAINT GREEN (-3100 3350);
DISPLAY INVISIBLE (-3100 3350);
FORCEPROP 2 LAST PATH I143
J 0
(-3175 3525);
DISPLAY 1.021277 (-3175 3525);
DISPLAY INVISIBLE (-3175 3525);
FORCEADD OFFPAGE..1
(-3225 3300);
FORCEPROP 2 LAST $XR0 20 
J 0
(-3446 3300);
DISPLAY 0.638298 (-3446 3300);
PAINT MONO (-3446 3300);
FORCEPROP 2 LAST CDS_LIB standard
J 0
(-3225 3300);
PAINT MONO (-3225 3300);
DISPLAY INVISIBLE (-3225 3300);
FORCEPROP 1 LAST OFFPAGE TRUE
J 0
(-2900 3175);
DISPLAY 0.872340 (-2900 3175);
DISPLAY INVISIBLE (-2900 3175);
FORCEPROP 1 LAST COMMENT_BODY TRUE
J 0
(-3100 3200);
DISPLAY 0.872340 (-3100 3200);
PAINT GREEN (-3100 3200);
DISPLAY INVISIBLE (-3100 3200);
FORCEPROP 2 LAST PATH I144
J 0
(-3175 3375);
DISPLAY 1.021277 (-3175 3375);
DISPLAY INVISIBLE (-3175 3375);
FORCEADD OFFPAGE..1
(-3225 3350);
FORCEPROP 2 LAST $XR0 20 
J 0
(-3446 3350);
DISPLAY 0.638298 (-3446 3350);
PAINT MONO (-3446 3350);
FORCEPROP 2 LAST CDS_LIB standard
J 0
(-3225 3350);
PAINT MONO (-3225 3350);
DISPLAY INVISIBLE (-3225 3350);
FORCEPROP 1 LAST OFFPAGE TRUE
J 0
(-2900 3225);
DISPLAY 0.872340 (-2900 3225);
DISPLAY INVISIBLE (-2900 3225);
FORCEPROP 1 LAST COMMENT_BODY TRUE
J 0
(-3100 3250);
DISPLAY 0.872340 (-3100 3250);
PAINT GREEN (-3100 3250);
DISPLAY INVISIBLE (-3100 3250);
FORCEPROP 2 LAST PATH I145
J 0
(-3175 3425);
DISPLAY 1.021277 (-3175 3425);
DISPLAY INVISIBLE (-3175 3425);
FORCEADD OFFPAGE..1
(-3225 3150);
FORCEPROP 2 LAST $XR0 20 
J 0
(-3446 3150);
DISPLAY 0.638298 (-3446 3150);
PAINT MONO (-3446 3150);
FORCEPROP 2 LAST CDS_LIB standard
J 0
(-3225 3150);
PAINT MONO (-3225 3150);
DISPLAY INVISIBLE (-3225 3150);
FORCEPROP 1 LAST OFFPAGE TRUE
J 0
(-2900 3025);
DISPLAY 0.872340 (-2900 3025);
DISPLAY INVISIBLE (-2900 3025);
FORCEPROP 1 LAST COMMENT_BODY TRUE
J 0
(-3100 3050);
DISPLAY 0.872340 (-3100 3050);
PAINT GREEN (-3100 3050);
DISPLAY INVISIBLE (-3100 3050);
FORCEPROP 2 LAST PATH I146
J 0
(-3175 3225);
DISPLAY 1.021277 (-3175 3225);
DISPLAY INVISIBLE (-3175 3225);
FORCEADD OFFPAGE..1
(-3225 3200);
FORCEPROP 2 LAST $XR0 20 
J 0
(-3446 3200);
DISPLAY 0.638298 (-3446 3200);
PAINT MONO (-3446 3200);
FORCEPROP 2 LAST CDS_LIB standard
J 0
(-3225 3200);
PAINT MONO (-3225 3200);
DISPLAY INVISIBLE (-3225 3200);
FORCEPROP 1 LAST OFFPAGE TRUE
J 0
(-2900 3075);
DISPLAY 0.872340 (-2900 3075);
DISPLAY INVISIBLE (-2900 3075);
FORCEPROP 1 LAST COMMENT_BODY TRUE
J 0
(-3100 3100);
DISPLAY 0.872340 (-3100 3100);
PAINT GREEN (-3100 3100);
DISPLAY INVISIBLE (-3100 3100);
FORCEPROP 2 LAST PATH I147
J 0
(-3175 3275);
DISPLAY 1.021277 (-3175 3275);
DISPLAY INVISIBLE (-3175 3275);
FORCEADD OFFPAGE..1
(-3225 3000);
FORCEPROP 2 LAST $XR0 20 
J 0
(-3446 3000);
DISPLAY 0.638298 (-3446 3000);
PAINT MONO (-3446 3000);
FORCEPROP 2 LAST CDS_LIB standard
J 0
(-3225 3000);
PAINT MONO (-3225 3000);
DISPLAY INVISIBLE (-3225 3000);
FORCEPROP 1 LAST OFFPAGE TRUE
J 0
(-2900 2875);
DISPLAY 0.872340 (-2900 2875);
DISPLAY INVISIBLE (-2900 2875);
FORCEPROP 1 LAST COMMENT_BODY TRUE
J 0
(-3100 2900);
DISPLAY 0.872340 (-3100 2900);
PAINT GREEN (-3100 2900);
DISPLAY INVISIBLE (-3100 2900);
FORCEPROP 2 LAST PATH I148
J 0
(-3175 3075);
DISPLAY 1.021277 (-3175 3075);
DISPLAY INVISIBLE (-3175 3075);
FORCEADD OFFPAGE..1
(-3225 3050);
FORCEPROP 2 LAST $XR0 20 
J 0
(-3446 3050);
DISPLAY 0.638298 (-3446 3050);
PAINT MONO (-3446 3050);
FORCEPROP 2 LAST CDS_LIB standard
J 0
(-3225 3050);
PAINT MONO (-3225 3050);
DISPLAY INVISIBLE (-3225 3050);
FORCEPROP 1 LAST OFFPAGE TRUE
J 0
(-2900 2925);
DISPLAY 0.872340 (-2900 2925);
DISPLAY INVISIBLE (-2900 2925);
FORCEPROP 1 LAST COMMENT_BODY TRUE
J 0
(-3100 2950);
DISPLAY 0.872340 (-3100 2950);
PAINT GREEN (-3100 2950);
DISPLAY INVISIBLE (-3100 2950);
FORCEPROP 2 LAST PATH I149
J 0
(-3175 3125);
DISPLAY 1.021277 (-3175 3125);
DISPLAY INVISIBLE (-3175 3125);
FORCEADD TAP..1
(-650 3700);
FORCEPROP 3 LASTPIN (-700 3700) SIG_NAME M_A_CPU0_SA_DQ<19>
J 0
(-690 3710);
DISPLAY 0.659574 (-690 3710);
PAINT MONO (-690 3710);
DISPLAY INVISIBLE (-690 3710);
FORCEPROP 1 LASTPIN (-700 3700) BN 19
J 0
(-712 3708);
DISPLAY 0.680851 (-712 3708);
PAINT GREEN (-712 3708);
FORCEPROP 2 LAST CDS_LIB standard
J 0
(-650 3700);
PAINT MONO (-650 3700);
DISPLAY INVISIBLE (-650 3700);
FORCEPROP 1 LAST BODY_TYPE PLUMBING
J 0
(-650 3750);
DISPLAY 0.872340 (-650 3750);
PAINT GREEN (-650 3750);
DISPLAY INVISIBLE (-650 3750);
FORCEPROP 1 LAST HDL_TAP TRUE
J 0
(-325 3575);
DISPLAY 0.872340 (-325 3575);
DISPLAY INVISIBLE (-325 3575);
FORCEPROP 1 LAST PATH I15
J 0
(-652 3700);
DISPLAY 0.872340 (-652 3700);
PAINT GREEN (-652 3700);
DISPLAY INVISIBLE (-652 3700);
FORCEADD TAP..1
R 2
(-2300 2600);
FORCEPROP 3 LASTPIN (-2250 2600) SIG_NAME M_A_CPU0_SA_CB<1>
J 0
(-2240 2610);
DISPLAY 0.659574 (-2240 2610);
PAINT MONO (-2240 2610);
DISPLAY INVISIBLE (-2240 2610);
FORCEPROP 1 LASTPIN (-2250 2600) BN 1
J 2
(-2238 2608);
DISPLAY 0.680851 (-2238 2608);
PAINT GREEN (-2238 2608);
FORCEPROP 2 LAST CDS_LIB standard
J 0
(-2300 2600);
DISPLAY INVISIBLE (-2300 2600);
FORCEPROP 1 LAST BODY_TYPE PLUMBING
J 2
(-2300 2650);
DISPLAY 0.872340 (-2300 2650);
PAINT GREEN (-2300 2650);
DISPLAY INVISIBLE (-2300 2650);
FORCEPROP 1 LAST HDL_TAP TRUE
J 2
(-2625 2475);
DISPLAY 0.872340 (-2625 2475);
DISPLAY INVISIBLE (-2625 2475);
FORCEPROP 1 LAST PATH I157
J 2
(-2298 2600);
DISPLAY 0.872340 (-2298 2600);
PAINT GREEN (-2298 2600);
DISPLAY INVISIBLE (-2298 2600);
FORCEADD TAP..1
R 2
(-2300 2650);
FORCEPROP 3 LASTPIN (-2250 2650) SIG_NAME M_A_CPU0_SA_CB<2>
J 0
(-2240 2660);
DISPLAY 0.659574 (-2240 2660);
PAINT MONO (-2240 2660);
DISPLAY INVISIBLE (-2240 2660);
FORCEPROP 1 LASTPIN (-2250 2650) BN 2
J 2
(-2238 2658);
DISPLAY 0.680851 (-2238 2658);
PAINT GREEN (-2238 2658);
FORCEPROP 2 LAST CDS_LIB standard
J 0
(-2300 2650);
DISPLAY INVISIBLE (-2300 2650);
FORCEPROP 1 LAST BODY_TYPE PLUMBING
J 2
(-2300 2700);
DISPLAY 0.872340 (-2300 2700);
PAINT GREEN (-2300 2700);
DISPLAY INVISIBLE (-2300 2700);
FORCEPROP 1 LAST HDL_TAP TRUE
J 2
(-2625 2525);
DISPLAY 0.872340 (-2625 2525);
DISPLAY INVISIBLE (-2625 2525);
FORCEPROP 1 LAST PATH I158
J 2
(-2298 2650);
DISPLAY 0.872340 (-2298 2650);
PAINT GREEN (-2298 2650);
DISPLAY INVISIBLE (-2298 2650);
FORCEADD TAP..1
(-650 3750);
FORCEPROP 3 LASTPIN (-700 3750) SIG_NAME M_A_CPU0_SA_DQ<20>
J 0
(-690 3760);
DISPLAY 0.659574 (-690 3760);
PAINT MONO (-690 3760);
DISPLAY INVISIBLE (-690 3760);
FORCEPROP 1 LASTPIN (-700 3750) BN 20
J 0
(-712 3758);
DISPLAY 0.680851 (-712 3758);
PAINT GREEN (-712 3758);
FORCEPROP 2 LAST CDS_LIB standard
J 0
(-650 3750);
PAINT MONO (-650 3750);
DISPLAY INVISIBLE (-650 3750);
FORCEPROP 1 LAST BODY_TYPE PLUMBING
J 0
(-650 3800);
DISPLAY 0.872340 (-650 3800);
PAINT GREEN (-650 3800);
DISPLAY INVISIBLE (-650 3800);
FORCEPROP 1 LAST HDL_TAP TRUE
J 0
(-325 3625);
DISPLAY 0.872340 (-325 3625);
DISPLAY INVISIBLE (-325 3625);
FORCEPROP 1 LAST PATH I16
J 0
(-652 3750);
DISPLAY 0.872340 (-652 3750);
PAINT GREEN (-652 3750);
DISPLAY INVISIBLE (-652 3750);
FORCEADD TAP..1
R 2
(-2300 2700);
FORCEPROP 3 LASTPIN (-2250 2700) SIG_NAME M_A_CPU0_SA_CB<3>
J 0
(-2240 2710);
DISPLAY 0.659574 (-2240 2710);
PAINT MONO (-2240 2710);
DISPLAY INVISIBLE (-2240 2710);
FORCEPROP 1 LASTPIN (-2250 2700) BN 3
J 2
(-2238 2708);
DISPLAY 0.680851 (-2238 2708);
PAINT GREEN (-2238 2708);
FORCEPROP 2 LAST CDS_LIB standard
J 0
(-2300 2700);
DISPLAY INVISIBLE (-2300 2700);
FORCEPROP 1 LAST BODY_TYPE PLUMBING
J 2
(-2300 2750);
DISPLAY 0.872340 (-2300 2750);
PAINT GREEN (-2300 2750);
DISPLAY INVISIBLE (-2300 2750);
FORCEPROP 1 LAST HDL_TAP TRUE
J 2
(-2625 2575);
DISPLAY 0.872340 (-2625 2575);
DISPLAY INVISIBLE (-2625 2575);
FORCEPROP 1 LAST PATH I160
J 2
(-2298 2700);
DISPLAY 0.872340 (-2298 2700);
PAINT GREEN (-2298 2700);
DISPLAY INVISIBLE (-2298 2700);
FORCEADD TAP..1
R 2
(-2300 2750);
FORCEPROP 3 LASTPIN (-2250 2750) SIG_NAME M_A_CPU0_SA_CB<4>
J 0
(-2240 2760);
DISPLAY 0.659574 (-2240 2760);
PAINT MONO (-2240 2760);
DISPLAY INVISIBLE (-2240 2760);
FORCEPROP 1 LASTPIN (-2250 2750) BN 4
J 2
(-2238 2758);
DISPLAY 0.680851 (-2238 2758);
PAINT GREEN (-2238 2758);
FORCEPROP 2 LAST CDS_LIB standard
J 0
(-2300 2750);
DISPLAY INVISIBLE (-2300 2750);
FORCEPROP 1 LAST BODY_TYPE PLUMBING
J 2
(-2300 2800);
DISPLAY 0.872340 (-2300 2800);
PAINT GREEN (-2300 2800);
DISPLAY INVISIBLE (-2300 2800);
FORCEPROP 1 LAST HDL_TAP TRUE
J 2
(-2625 2625);
DISPLAY 0.872340 (-2625 2625);
DISPLAY INVISIBLE (-2625 2625);
FORCEPROP 1 LAST PATH I161
J 2
(-2298 2750);
DISPLAY 0.872340 (-2298 2750);
PAINT GREEN (-2298 2750);
DISPLAY INVISIBLE (-2298 2750);
FORCEADD TAP..1
R 2
(-2300 2800);
FORCEPROP 3 LASTPIN (-2250 2800) SIG_NAME M_A_CPU0_SA_CB<5>
J 0
(-2240 2810);
DISPLAY 0.659574 (-2240 2810);
PAINT MONO (-2240 2810);
DISPLAY INVISIBLE (-2240 2810);
FORCEPROP 1 LASTPIN (-2250 2800) BN 5
J 2
(-2238 2808);
DISPLAY 0.680851 (-2238 2808);
PAINT GREEN (-2238 2808);
FORCEPROP 2 LAST CDS_LIB standard
J 0
(-2300 2800);
DISPLAY INVISIBLE (-2300 2800);
FORCEPROP 1 LAST BODY_TYPE PLUMBING
J 2
(-2300 2850);
DISPLAY 0.872340 (-2300 2850);
PAINT GREEN (-2300 2850);
DISPLAY INVISIBLE (-2300 2850);
FORCEPROP 1 LAST HDL_TAP TRUE
J 2
(-2625 2675);
DISPLAY 0.872340 (-2625 2675);
DISPLAY INVISIBLE (-2625 2675);
FORCEPROP 1 LAST PATH I162
J 2
(-2298 2800);
DISPLAY 0.872340 (-2298 2800);
PAINT GREEN (-2298 2800);
DISPLAY INVISIBLE (-2298 2800);
FORCEADD TAP..1
R 2
(-2300 2850);
FORCEPROP 3 LASTPIN (-2250 2850) SIG_NAME M_A_CPU0_SA_CB<6>
J 0
(-2240 2860);
DISPLAY 0.659574 (-2240 2860);
PAINT MONO (-2240 2860);
DISPLAY INVISIBLE (-2240 2860);
FORCEPROP 1 LASTPIN (-2250 2850) BN 6
J 2
(-2238 2858);
DISPLAY 0.680851 (-2238 2858);
PAINT GREEN (-2238 2858);
FORCEPROP 2 LAST CDS_LIB standard
J 0
(-2300 2850);
DISPLAY INVISIBLE (-2300 2850);
FORCEPROP 1 LAST BODY_TYPE PLUMBING
J 2
(-2300 2900);
DISPLAY 0.872340 (-2300 2900);
PAINT GREEN (-2300 2900);
DISPLAY INVISIBLE (-2300 2900);
FORCEPROP 1 LAST HDL_TAP TRUE
J 2
(-2625 2725);
DISPLAY 0.872340 (-2625 2725);
DISPLAY INVISIBLE (-2625 2725);
FORCEPROP 1 LAST PATH I163
J 2
(-2298 2850);
DISPLAY 0.872340 (-2298 2850);
PAINT GREEN (-2298 2850);
DISPLAY INVISIBLE (-2298 2850);
FORCEADD TAP..1
R 2
(-2300 2900);
FORCEPROP 3 LASTPIN (-2250 2900) SIG_NAME M_A_CPU0_SA_CB<7>
J 0
(-2240 2910);
DISPLAY 0.659574 (-2240 2910);
PAINT MONO (-2240 2910);
DISPLAY INVISIBLE (-2240 2910);
FORCEPROP 1 LASTPIN (-2250 2900) BN 7
J 2
(-2238 2908);
DISPLAY 0.680851 (-2238 2908);
PAINT GREEN (-2238 2908);
FORCEPROP 2 LAST CDS_LIB standard
J 0
(-2300 2900);
DISPLAY INVISIBLE (-2300 2900);
FORCEPROP 1 LAST BODY_TYPE PLUMBING
J 2
(-2300 2950);
DISPLAY 0.872340 (-2300 2950);
PAINT GREEN (-2300 2950);
DISPLAY INVISIBLE (-2300 2950);
FORCEPROP 1 LAST HDL_TAP TRUE
J 2
(-2625 2775);
DISPLAY 0.872340 (-2625 2775);
DISPLAY INVISIBLE (-2625 2775);
FORCEPROP 1 LAST PATH I164
J 2
(-2298 2900);
DISPLAY 0.872340 (-2298 2900);
PAINT GREEN (-2298 2900);
DISPLAY INVISIBLE (-2298 2900);
FORCEADD TAP..1
R 2
(-2300 2550);
FORCEPROP 3 LASTPIN (-2250 2550) SIG_NAME M_A_CPU0_SA_CB<0>
J 0
(-2240 2560);
DISPLAY 0.659574 (-2240 2560);
PAINT MONO (-2240 2560);
DISPLAY INVISIBLE (-2240 2560);
FORCEPROP 1 LASTPIN (-2250 2550) BN 0
J 2
(-2238 2558);
DISPLAY 0.680851 (-2238 2558);
PAINT GREEN (-2238 2558);
FORCEPROP 2 LAST CDS_LIB standard
J 0
(-2300 2550);
PAINT MONO (-2300 2550);
DISPLAY INVISIBLE (-2300 2550);
FORCEPROP 1 LAST BODY_TYPE PLUMBING
J 2
(-2300 2600);
DISPLAY 0.872340 (-2300 2600);
PAINT GREEN (-2300 2600);
DISPLAY INVISIBLE (-2300 2600);
FORCEPROP 1 LAST HDL_TAP TRUE
J 2
(-2625 2425);
DISPLAY 0.872340 (-2625 2425);
DISPLAY INVISIBLE (-2625 2425);
FORCEPROP 1 LAST PATH I165
J 2
(-2298 2550);
DISPLAY 0.872340 (-2298 2550);
PAINT GREEN (-2298 2550);
DISPLAY INVISIBLE (-2298 2550);
FORCEADD OFFPAGE..3
R 2
(-3225 2925);
FORCEPROP 2 LAST $XR1 83 
J 0
(-3564 2925);
DISPLAY 0.638298 (-3564 2925);
PAINT MONO (-3564 2925);
FORCEPROP 2 LAST $XR0 20 
J 0
(-3474 2925);
DISPLAY 0.638298 (-3474 2925);
PAINT MONO (-3474 2925);
FORCEPROP 2 LAST CDS_LIB standard
J 0
(-3225 2925);
PAINT MONO (-3225 2925);
DISPLAY INVISIBLE (-3225 2925);
FORCEPROP 1 LAST OFFPAGE TRUE
J 2
(-3550 2800);
DISPLAY 0.872340 (-3550 2800);
DISPLAY INVISIBLE (-3550 2800);
FORCEPROP 1 LAST COMMENT_BODY TRUE
J 2
(-3175 2825);
DISPLAY 0.872340 (-3175 2825);
PAINT GREEN (-3175 2825);
DISPLAY INVISIBLE (-3175 2825);
FORCEPROP 2 LAST PATH I166
J 0
(-3175 3000);
DISPLAY 1.021277 (-3175 3000);
DISPLAY INVISIBLE (-3175 3000);
FORCEADD TAP..1
R 2
(-2300 2100);
FORCEPROP 3 LASTPIN (-2250 2100) SIG_NAME M_A_CPU0_SB_CB<0>
J 0
(-2240 2110);
DISPLAY 0.659574 (-2240 2110);
PAINT MONO (-2240 2110);
DISPLAY INVISIBLE (-2240 2110);
FORCEPROP 1 LASTPIN (-2250 2100) BN 0
J 2
(-2238 2108);
DISPLAY 0.680851 (-2238 2108);
PAINT GREEN (-2238 2108);
FORCEPROP 2 LAST CDS_LIB standard
J 0
(-2300 2100);
PAINT MONO (-2300 2100);
DISPLAY INVISIBLE (-2300 2100);
FORCEPROP 1 LAST BODY_TYPE PLUMBING
J 2
(-2300 2150);
DISPLAY 0.872340 (-2300 2150);
PAINT GREEN (-2300 2150);
DISPLAY INVISIBLE (-2300 2150);
FORCEPROP 1 LAST HDL_TAP TRUE
J 2
(-2625 1975);
DISPLAY 0.872340 (-2625 1975);
DISPLAY INVISIBLE (-2625 1975);
FORCEPROP 1 LAST PATH I167
J 2
(-2298 2100);
DISPLAY 0.872340 (-2298 2100);
PAINT GREEN (-2298 2100);
DISPLAY INVISIBLE (-2298 2100);
FORCEADD TAP..1
R 2
(-2300 2450);
FORCEPROP 3 LASTPIN (-2250 2450) SIG_NAME M_A_CPU0_SB_CB<7>
J 0
(-2240 2460);
DISPLAY 0.659574 (-2240 2460);
PAINT MONO (-2240 2460);
DISPLAY INVISIBLE (-2240 2460);
FORCEPROP 1 LASTPIN (-2250 2450) BN 7
J 2
(-2238 2458);
DISPLAY 0.680851 (-2238 2458);
PAINT GREEN (-2238 2458);
FORCEPROP 2 LAST CDS_LIB standard
J 0
(-2300 2450);
DISPLAY INVISIBLE (-2300 2450);
FORCEPROP 1 LAST BODY_TYPE PLUMBING
J 2
(-2300 2500);
DISPLAY 0.872340 (-2300 2500);
PAINT GREEN (-2300 2500);
DISPLAY INVISIBLE (-2300 2500);
FORCEPROP 1 LAST HDL_TAP TRUE
J 2
(-2625 2325);
DISPLAY 0.872340 (-2625 2325);
DISPLAY INVISIBLE (-2625 2325);
FORCEPROP 1 LAST PATH I168
J 2
(-2298 2450);
DISPLAY 0.872340 (-2298 2450);
PAINT GREEN (-2298 2450);
DISPLAY INVISIBLE (-2298 2450);
FORCEADD TAP..1
R 2
(-2300 2400);
FORCEPROP 3 LASTPIN (-2250 2400) SIG_NAME M_A_CPU0_SB_CB<6>
J 0
(-2240 2410);
DISPLAY 0.659574 (-2240 2410);
PAINT MONO (-2240 2410);
DISPLAY INVISIBLE (-2240 2410);
FORCEPROP 1 LASTPIN (-2250 2400) BN 6
J 2
(-2238 2408);
DISPLAY 0.680851 (-2238 2408);
PAINT GREEN (-2238 2408);
FORCEPROP 2 LAST CDS_LIB standard
J 0
(-2300 2400);
DISPLAY INVISIBLE (-2300 2400);
FORCEPROP 1 LAST BODY_TYPE PLUMBING
J 2
(-2300 2450);
DISPLAY 0.872340 (-2300 2450);
PAINT GREEN (-2300 2450);
DISPLAY INVISIBLE (-2300 2450);
FORCEPROP 1 LAST HDL_TAP TRUE
J 2
(-2625 2275);
DISPLAY 0.872340 (-2625 2275);
DISPLAY INVISIBLE (-2625 2275);
FORCEPROP 1 LAST PATH I169
J 2
(-2298 2400);
DISPLAY 0.872340 (-2298 2400);
PAINT GREEN (-2298 2400);
DISPLAY INVISIBLE (-2298 2400);
FORCEADD TAP..1
(-650 3800);
FORCEPROP 3 LASTPIN (-700 3800) SIG_NAME M_A_CPU0_SA_DQ<21>
J 0
(-690 3810);
DISPLAY 0.659574 (-690 3810);
PAINT MONO (-690 3810);
DISPLAY INVISIBLE (-690 3810);
FORCEPROP 1 LASTPIN (-700 3800) BN 21
J 0
(-712 3808);
DISPLAY 0.680851 (-712 3808);
PAINT GREEN (-712 3808);
FORCEPROP 2 LAST CDS_LIB standard
J 0
(-650 3800);
PAINT MONO (-650 3800);
DISPLAY INVISIBLE (-650 3800);
FORCEPROP 1 LAST BODY_TYPE PLUMBING
J 0
(-650 3850);
DISPLAY 0.872340 (-650 3850);
PAINT GREEN (-650 3850);
DISPLAY INVISIBLE (-650 3850);
FORCEPROP 1 LAST HDL_TAP TRUE
J 0
(-325 3675);
DISPLAY 0.872340 (-325 3675);
DISPLAY INVISIBLE (-325 3675);
FORCEPROP 1 LAST PATH I17
J 0
(-652 3800);
DISPLAY 0.872340 (-652 3800);
PAINT GREEN (-652 3800);
DISPLAY INVISIBLE (-652 3800);
FORCEADD TAP..1
R 2
(-2300 2350);
FORCEPROP 3 LASTPIN (-2250 2350) SIG_NAME M_A_CPU0_SB_CB<5>
J 0
(-2240 2360);
DISPLAY 0.659574 (-2240 2360);
PAINT MONO (-2240 2360);
DISPLAY INVISIBLE (-2240 2360);
FORCEPROP 1 LASTPIN (-2250 2350) BN 5
J 2
(-2238 2358);
DISPLAY 0.680851 (-2238 2358);
PAINT GREEN (-2238 2358);
FORCEPROP 2 LAST CDS_LIB standard
J 0
(-2300 2350);
DISPLAY INVISIBLE (-2300 2350);
FORCEPROP 1 LAST BODY_TYPE PLUMBING
J 2
(-2300 2400);
DISPLAY 0.872340 (-2300 2400);
PAINT GREEN (-2300 2400);
DISPLAY INVISIBLE (-2300 2400);
FORCEPROP 1 LAST HDL_TAP TRUE
J 2
(-2625 2225);
DISPLAY 0.872340 (-2625 2225);
DISPLAY INVISIBLE (-2625 2225);
FORCEPROP 1 LAST PATH I170
J 2
(-2298 2350);
DISPLAY 0.872340 (-2298 2350);
PAINT GREEN (-2298 2350);
DISPLAY INVISIBLE (-2298 2350);
FORCEADD TAP..1
R 2
(-2300 2300);
FORCEPROP 3 LASTPIN (-2250 2300) SIG_NAME M_A_CPU0_SB_CB<4>
J 0
(-2240 2310);
DISPLAY 0.659574 (-2240 2310);
PAINT MONO (-2240 2310);
DISPLAY INVISIBLE (-2240 2310);
FORCEPROP 1 LASTPIN (-2250 2300) BN 4
J 2
(-2238 2308);
DISPLAY 0.680851 (-2238 2308);
PAINT GREEN (-2238 2308);
FORCEPROP 2 LAST CDS_LIB standard
J 0
(-2300 2300);
DISPLAY INVISIBLE (-2300 2300);
FORCEPROP 1 LAST BODY_TYPE PLUMBING
J 2
(-2300 2350);
DISPLAY 0.872340 (-2300 2350);
PAINT GREEN (-2300 2350);
DISPLAY INVISIBLE (-2300 2350);
FORCEPROP 1 LAST HDL_TAP TRUE
J 2
(-2625 2175);
DISPLAY 0.872340 (-2625 2175);
DISPLAY INVISIBLE (-2625 2175);
FORCEPROP 1 LAST PATH I171
J 2
(-2298 2300);
DISPLAY 0.872340 (-2298 2300);
PAINT GREEN (-2298 2300);
DISPLAY INVISIBLE (-2298 2300);
FORCEADD TAP..1
R 2
(-2300 2250);
FORCEPROP 3 LASTPIN (-2250 2250) SIG_NAME M_A_CPU0_SB_CB<3>
J 0
(-2240 2260);
DISPLAY 0.659574 (-2240 2260);
PAINT MONO (-2240 2260);
DISPLAY INVISIBLE (-2240 2260);
FORCEPROP 1 LASTPIN (-2250 2250) BN 3
J 2
(-2238 2258);
DISPLAY 0.680851 (-2238 2258);
PAINT GREEN (-2238 2258);
FORCEPROP 2 LAST CDS_LIB standard
J 0
(-2300 2250);
DISPLAY INVISIBLE (-2300 2250);
FORCEPROP 1 LAST BODY_TYPE PLUMBING
J 2
(-2300 2300);
DISPLAY 0.872340 (-2300 2300);
PAINT GREEN (-2300 2300);
DISPLAY INVISIBLE (-2300 2300);
FORCEPROP 1 LAST HDL_TAP TRUE
J 2
(-2625 2125);
DISPLAY 0.872340 (-2625 2125);
DISPLAY INVISIBLE (-2625 2125);
FORCEPROP 1 LAST PATH I172
J 2
(-2298 2250);
DISPLAY 0.872340 (-2298 2250);
PAINT GREEN (-2298 2250);
DISPLAY INVISIBLE (-2298 2250);
FORCEADD TAP..1
R 2
(-2300 2200);
FORCEPROP 3 LASTPIN (-2250 2200) SIG_NAME M_A_CPU0_SB_CB<2>
J 0
(-2240 2210);
DISPLAY 0.659574 (-2240 2210);
PAINT MONO (-2240 2210);
DISPLAY INVISIBLE (-2240 2210);
FORCEPROP 1 LASTPIN (-2250 2200) BN 2
J 2
(-2238 2208);
DISPLAY 0.680851 (-2238 2208);
PAINT GREEN (-2238 2208);
FORCEPROP 2 LAST CDS_LIB standard
J 0
(-2300 2200);
DISPLAY INVISIBLE (-2300 2200);
FORCEPROP 1 LAST BODY_TYPE PLUMBING
J 2
(-2300 2250);
DISPLAY 0.872340 (-2300 2250);
PAINT GREEN (-2300 2250);
DISPLAY INVISIBLE (-2300 2250);
FORCEPROP 1 LAST HDL_TAP TRUE
J 2
(-2625 2075);
DISPLAY 0.872340 (-2625 2075);
DISPLAY INVISIBLE (-2625 2075);
FORCEPROP 1 LAST PATH I173
J 2
(-2298 2200);
DISPLAY 0.872340 (-2298 2200);
PAINT GREEN (-2298 2200);
DISPLAY INVISIBLE (-2298 2200);
FORCEADD TAP..1
R 2
(-2300 2150);
FORCEPROP 3 LASTPIN (-2250 2150) SIG_NAME M_A_CPU0_SB_CB<1>
J 0
(-2240 2160);
DISPLAY 0.659574 (-2240 2160);
PAINT MONO (-2240 2160);
DISPLAY INVISIBLE (-2240 2160);
FORCEPROP 1 LASTPIN (-2250 2150) BN 1
J 2
(-2238 2158);
DISPLAY 0.680851 (-2238 2158);
PAINT GREEN (-2238 2158);
FORCEPROP 2 LAST CDS_LIB standard
J 0
(-2300 2150);
DISPLAY INVISIBLE (-2300 2150);
FORCEPROP 1 LAST BODY_TYPE PLUMBING
J 2
(-2300 2200);
DISPLAY 0.872340 (-2300 2200);
PAINT GREEN (-2300 2200);
DISPLAY INVISIBLE (-2300 2200);
FORCEPROP 1 LAST HDL_TAP TRUE
J 2
(-2625 2025);
DISPLAY 0.872340 (-2625 2025);
DISPLAY INVISIBLE (-2625 2025);
FORCEPROP 1 LAST PATH I174
J 2
(-2298 2150);
DISPLAY 0.872340 (-2298 2150);
PAINT GREEN (-2298 2150);
DISPLAY INVISIBLE (-2298 2150);
FORCEADD OFFPAGE..3
R 2
(-3225 2475);
FORCEPROP 2 LAST $XR1 83 
J 0
(-3564 2475);
DISPLAY 0.638298 (-3564 2475);
PAINT MONO (-3564 2475);
FORCEPROP 2 LAST $XR0 20 
J 0
(-3474 2475);
DISPLAY 0.638298 (-3474 2475);
PAINT MONO (-3474 2475);
FORCEPROP 2 LAST CDS_LIB standard
J 0
(-3225 2475);
PAINT MONO (-3225 2475);
DISPLAY INVISIBLE (-3225 2475);
FORCEPROP 1 LAST OFFPAGE TRUE
J 2
(-3550 2350);
DISPLAY 0.872340 (-3550 2350);
DISPLAY INVISIBLE (-3550 2350);
FORCEPROP 1 LAST COMMENT_BODY TRUE
J 2
(-3175 2375);
DISPLAY 0.872340 (-3175 2375);
PAINT GREEN (-3175 2375);
DISPLAY INVISIBLE (-3175 2375);
FORCEPROP 2 LAST PATH I175
J 0
(-3175 2550);
DISPLAY 1.021277 (-3175 2550);
DISPLAY INVISIBLE (-3175 2550);
FORCEADD OFFPAGE..1
(-3200 2050);
FORCEPROP 2 LAST $XR3 85 
J 0
(-3752 2050);
DISPLAY 0.638298 (-3752 2050);
PAINT MONO (-3752 2050);
FORCEPROP 2 LAST $XR2 84 
J 0
(-3662 2050);
DISPLAY 0.638298 (-3662 2050);
PAINT MONO (-3662 2050);
FORCEPROP 2 LAST $XR1 83 
J 0
(-3572 2050);
DISPLAY 0.638298 (-3572 2050);
PAINT MONO (-3572 2050);
FORCEPROP 2 LAST $XR0 129 
J 0
(-3482 2050);
DISPLAY 0.638298 (-3482 2050);
PAINT MONO (-3482 2050);
FORCEPROP 2 LAST CDS_LIB standard
J 0
(-3200 2050);
PAINT MONO (-3200 2050);
DISPLAY INVISIBLE (-3200 2050);
FORCEPROP 1 LAST OFFPAGE TRUE
J 0
(-2875 1925);
DISPLAY 0.872340 (-2875 1925);
DISPLAY INVISIBLE (-2875 1925);
FORCEPROP 1 LAST COMMENT_BODY TRUE
J 0
(-3075 1950);
DISPLAY 0.872340 (-3075 1950);
PAINT GREEN (-3075 1950);
DISPLAY INVISIBLE (-3075 1950);
FORCEPROP 2 LAST PATH I176
J 0
(-3150 2125);
DISPLAY 1.021277 (-3150 2125);
DISPLAY INVISIBLE (-3150 2125);
FORCEADD OFFPAGE..1
(-3200 1950);
FORCEPROP 2 LAST $XR1 83 
J 0
(-3541 1950);
DISPLAY 0.638298 (-3541 1950);
PAINT MONO (-3541 1950);
FORCEPROP 2 LAST $XR0 20 
J 0
(-3451 1950);
DISPLAY 0.638298 (-3451 1950);
PAINT MONO (-3451 1950);
FORCEPROP 2 LAST CDS_LIB standard
J 0
(-3200 1950);
PAINT MONO (-3200 1950);
DISPLAY INVISIBLE (-3200 1950);
FORCEPROP 1 LAST OFFPAGE TRUE
J 0
(-2875 1825);
DISPLAY 0.872340 (-2875 1825);
DISPLAY INVISIBLE (-2875 1825);
FORCEPROP 1 LAST COMMENT_BODY TRUE
J 0
(-3075 1850);
DISPLAY 0.872340 (-3075 1850);
PAINT GREEN (-3075 1850);
DISPLAY INVISIBLE (-3075 1850);
FORCEPROP 2 LAST PATH I177
J 0
(-3150 2025);
DISPLAY 1.021277 (-3150 2025);
DISPLAY INVISIBLE (-3150 2025);
FORCEADD OFFPAGE..1
(-3125 1800);
FORCEPROP 2 LAST $XR0 82 
J 0
(-3346 1800);
DISPLAY 0.638298 (-3346 1800);
PAINT MONO (-3346 1800);
FORCEPROP 2 LAST CDS_LIB standard
J 0
(-3125 1800);
PAINT MONO (-3125 1800);
DISPLAY INVISIBLE (-3125 1800);
FORCEPROP 1 LAST OFFPAGE TRUE
J 0
(-2800 1675);
DISPLAY 0.872340 (-2800 1675);
DISPLAY INVISIBLE (-2800 1675);
FORCEPROP 1 LAST COMMENT_BODY TRUE
J 0
(-3000 1700);
DISPLAY 0.872340 (-3000 1700);
PAINT GREEN (-3000 1700);
DISPLAY INVISIBLE (-3000 1700);
FORCEPROP 2 LAST PATH I178
J 0
(-3075 1875);
DISPLAY 1.021277 (-3075 1875);
DISPLAY INVISIBLE (-3075 1875);
FORCEADD TAP..1
(-650 3650);
FORCEPROP 3 LASTPIN (-700 3650) SIG_NAME M_A_CPU0_SA_DQ<18>
J 0
(-690 3660);
DISPLAY 0.659574 (-690 3660);
PAINT MONO (-690 3660);
DISPLAY INVISIBLE (-690 3660);
FORCEPROP 1 LASTPIN (-700 3650) BN 18
J 0
(-712 3658);
DISPLAY 0.680851 (-712 3658);
PAINT GREEN (-712 3658);
FORCEPROP 2 LAST CDS_LIB standard
J 0
(-650 3650);
PAINT MONO (-650 3650);
DISPLAY INVISIBLE (-650 3650);
FORCEPROP 1 LAST BODY_TYPE PLUMBING
J 0
(-650 3700);
DISPLAY 0.872340 (-650 3700);
PAINT GREEN (-650 3700);
DISPLAY INVISIBLE (-650 3700);
FORCEPROP 1 LAST HDL_TAP TRUE
J 0
(-325 3525);
DISPLAY 0.872340 (-325 3525);
DISPLAY INVISIBLE (-325 3525);
FORCEPROP 1 LAST PATH I18
J 0
(-652 3650);
DISPLAY 0.872340 (-652 3650);
PAINT GREEN (-652 3650);
DISPLAY INVISIBLE (-652 3650);
FORCEADD OFFPAGE..1
(-3125 1750);
FORCEPROP 2 LAST $XR7 89 
J 0
(-3377 1714);
DISPLAY 0.638298 (-3377 1714);
PAINT MONO (-3377 1714);
FORCEPROP 2 LAST $XR6 88 
J 0
(-3917 1750);
DISPLAY 0.638298 (-3917 1750);
PAINT MONO (-3917 1750);
FORCEPROP 2 LAST $XR5 87 
J 0
(-3827 1750);
DISPLAY 0.638298 (-3827 1750);
PAINT MONO (-3827 1750);
FORCEPROP 2 LAST $XR4 86 
J 0
(-3737 1750);
DISPLAY 0.638298 (-3737 1750);
PAINT MONO (-3737 1750);
FORCEPROP 2 LAST $XR3 85 
J 0
(-3647 1750);
DISPLAY 0.638298 (-3647 1750);
PAINT MONO (-3647 1750);
FORCEPROP 2 LAST $XR2 84 
J 0
(-3557 1750);
DISPLAY 0.638298 (-3557 1750);
PAINT MONO (-3557 1750);
FORCEPROP 2 LAST $XR1 83 
J 0
(-3467 1750);
DISPLAY 0.638298 (-3467 1750);
PAINT MONO (-3467 1750);
FORCEPROP 2 LAST $XR0 229 
J 0
(-3377 1750);
DISPLAY 0.638298 (-3377 1750);
PAINT MONO (-3377 1750);
FORCEPROP 2 LAST CDS_LIB standard
J 0
(-3125 1750);
PAINT MONO (-3125 1750);
DISPLAY INVISIBLE (-3125 1750);
FORCEPROP 1 LAST OFFPAGE TRUE
J 0
(-2800 1625);
DISPLAY 0.872340 (-2800 1625);
DISPLAY INVISIBLE (-2800 1625);
FORCEPROP 1 LAST COMMENT_BODY TRUE
J 0
(-3000 1650);
DISPLAY 0.872340 (-3000 1650);
PAINT GREEN (-3000 1650);
DISPLAY INVISIBLE (-3000 1650);
FORCEPROP 2 LAST PATH I180
J 0
(-3075 1825);
DISPLAY 1.021277 (-3075 1825);
DISPLAY INVISIBLE (-3075 1825);
FORCEADD OFFPAGE..2
R 2
(-3225 900);
FORCEPROP 2 LAST $XR0 20 
J 0
(-3479 900);
DISPLAY 0.638298 (-3479 900);
PAINT MONO (-3479 900);
FORCEPROP 2 LAST CDS_LIB standard
J 0
(-3225 900);
PAINT MONO (-3225 900);
DISPLAY INVISIBLE (-3225 900);
FORCEPROP 1 LAST OFFPAGE TRUE
J 2
(-3550 775);
DISPLAY 0.872340 (-3550 775);
DISPLAY INVISIBLE (-3550 775);
FORCEPROP 1 LAST COMMENT_BODY TRUE
J 2
(-3180 805);
DISPLAY 0.872340 (-3180 805);
PAINT GREEN (-3180 805);
DISPLAY INVISIBLE (-3180 805);
FORCEPROP 2 LAST PATH I181
J 0
(-3175 975);
DISPLAY 1.021277 (-3175 975);
DISPLAY INVISIBLE (-3175 975);
FORCEADD OFFPAGE..2
R 2
(-3225 850);
FORCEPROP 2 LAST $XR0 20 
J 0
(-3479 850);
DISPLAY 0.638298 (-3479 850);
PAINT MONO (-3479 850);
FORCEPROP 2 LAST CDS_LIB standard
J 0
(-3225 850);
PAINT MONO (-3225 850);
DISPLAY INVISIBLE (-3225 850);
FORCEPROP 1 LAST OFFPAGE TRUE
J 2
(-3550 725);
DISPLAY 0.872340 (-3550 725);
DISPLAY INVISIBLE (-3550 725);
FORCEPROP 1 LAST COMMENT_BODY TRUE
J 2
(-3180 755);
DISPLAY 0.872340 (-3180 755);
PAINT GREEN (-3180 755);
DISPLAY INVISIBLE (-3180 755);
FORCEPROP 2 LAST PATH I182
J 0
(-3175 925);
DISPLAY 1.021277 (-3175 925);
DISPLAY INVISIBLE (-3175 925);
FORCEADD VCC_CORE..1
(-3125 2175);
FORCEPROP 3 LASTPIN (-3125 2125) SIG_NAME P3V3_AUX\g
J 0
(-3115 2135);
DISPLAY 0.659574 (-3115 2135);
PAINT MONO (-3115 2135);
DISPLAY INVISIBLE (-3115 2135);
FORCEPROP 1 LAST HDL_POWER P3V3_AUX
J 1
(-3125 2225);
DISPLAY 1.148936 (-3125 2225);
PAINT GREEN (-3125 2225);
FORCEPROP 2 LAST CDS_LIB logical_power
J 0
(-3125 2175);
PAINT MONO (-3125 2175);
DISPLAY INVISIBLE (-3125 2175);
FORCEPROP 1 LAST PATH I183
J 0
(-3075 2200);
DISPLAY 0.872340 (-3075 2200);
PAINT AQUA (-3075 2200);
DISPLAY INVISIBLE (-3075 2200);
FORCEADD UNIVERSAL_GND..1
(5475 600);
FORCEPROP 3 LASTPIN (5475 650) SIG_NAME GND\g
J 0
(5485 660);
DISPLAY 0.659574 (5485 660);
PAINT MONO (5485 660);
DISPLAY INVISIBLE (5485 660);
FORCEPROP 2 LAST CDS_LIB logical_power
J 0
(5475 600);
PAINT MONO (5475 600);
DISPLAY INVISIBLE (5475 600);
FORCEPROP 1 LAST HDL_POWER GND
J 1
(5500 525);
DISPLAY 0.872340 (5500 525);
PAINT GREEN (5500 525);
DISPLAY INVISIBLE (5500 525);
FORCEPROP 1 LAST PATH I184
J 0
(5550 600);
DISPLAY 0.872340 (5550 600);
PAINT AQUA (5550 600);
DISPLAY INVISIBLE (5550 600);
FORCEADD UNIVERSAL_GND..1
(3775 600);
FORCEPROP 3 LASTPIN (3775 650) SIG_NAME GND\g
J 0
(3785 660);
DISPLAY 0.659574 (3785 660);
PAINT MONO (3785 660);
DISPLAY INVISIBLE (3785 660);
FORCEPROP 2 LAST CDS_LIB logical_power
J 0
(3775 600);
PAINT MONO (3775 600);
DISPLAY INVISIBLE (3775 600);
FORCEPROP 1 LAST HDL_POWER GND
J 1
(3800 525);
DISPLAY 0.872340 (3800 525);
PAINT GREEN (3800 525);
DISPLAY INVISIBLE (3800 525);
FORCEPROP 1 LAST PATH I185
J 0
(3850 600);
DISPLAY 0.872340 (3850 600);
PAINT AQUA (3850 600);
DISPLAY INVISIBLE (3850 600);
FORCEADD VCC_CORE..1
(3775 4850);
FORCEPROP 3 LASTPIN (3775 4800) SIG_NAME P12V_S3_AUX_CPU0_NVDIMM\g
J 0
(3785 4810);
DISPLAY 0.659574 (3785 4810);
PAINT MONO (3785 4810);
DISPLAY INVISIBLE (3785 4810);
FORCEPROP 1 LAST HDL_POWER P12V_S3_AUX_CPU0_NVDIMM
J 1
(3775 4900);
DISPLAY 1.148936 (3775 4900);
PAINT GREEN (3775 4900);
FORCEPROP 2 LAST CDS_LIB logical_power
J 0
(3775 4850);
PAINT MONO (3775 4850);
DISPLAY INVISIBLE (3775 4850);
FORCEPROP 1 LAST PATH I186
J 0
(3825 4875);
DISPLAY 0.872340 (3825 4875);
PAINT AQUA (3825 4875);
DISPLAY INVISIBLE (3825 4875);
FORCEADD VCC_CORE..1
(2075 750);
FORCEPROP 3 LASTPIN (2075 700) SIG_NAME P12V_S3_AUX_CPU0_NVDIMM\g
J 0
(2085 710);
DISPLAY 0.659574 (2085 710);
PAINT MONO (2085 710);
DISPLAY INVISIBLE (2085 710);
FORCEPROP 1 LAST HDL_POWER P12V_S3_AUX_CPU0_NVDIMM
J 1
(2075 800);
DISPLAY 1.148936 (2075 800);
PAINT GREEN (2075 800);
FORCEPROP 2 LAST CDS_LIB logical_power
J 0
(2075 750);
PAINT MONO (2075 750);
DISPLAY INVISIBLE (2075 750);
FORCEPROP 1 LAST PATH I187
J 0
(2125 775);
DISPLAY 0.872340 (2125 775);
PAINT AQUA (2125 775);
DISPLAY INVISIBLE (2125 775);
FORCEADD Q_CAP..1
(2075 425);
FORCEPROP 1 LAST PART_NUMBER CH6103KEA00
J 0
(2125 275);
DISPLAY 0.978723 (2125 275);
DISPLAY INVISIBLE (2125 275);
FORCEPROP 1 LAST MATERIAL X6S
J 0
(2125 325);
DISPLAY 0.978723 (2125 325);
FORCEPROP 1 LAST PACK_TYPE C0805
J 0
(2125 225);
DISPLAY 0.978723 (2125 225);
FORCEPROP 1 LAST TOLERANCE 10%
J 0
(2125 375);
DISPLAY 0.978723 (2125 375);
FORCEPROP 1 LAST VALUE 10UF
J 0
(2125 475);
DISPLAY 0.978723 (2125 475);
FORCEPROP 1 LAST VOLTAGE 16V
J 0
(2125 425);
DISPLAY 0.978723 (2125 425);
FORCEPROP 1 LAST $LOCATION C3
J 0
(2125 525);
DISPLAY 0.978723 (2125 525);
FORCEPROP 1 LASTPIN (2075 525) $PN 1
J 0
(2085 505);
DISPLAY 0.787234 (2085 505);
FORCEPROP 1 LASTPIN (2075 325) $PN 2
J 0
(2085 305);
DISPLAY 0.787234 (2085 305);
FORCEPROP 2 LAST CDS_LIB pure_quanta
J 0
(2075 425);
PAINT MONO (2075 425);
DISPLAY INVISIBLE (2075 425);
FORCEPROP 2 LAST CDS_LOCATION C3
J 0
(2125 625);
DISPLAY 1.021277 (2125 625);
DISPLAY INVISIBLE (2125 625);
FORCEPROP 2 LAST $SEC 1
J 0
(2125 625);
DISPLAY 0.680851 (2125 625);
PAINT MONO (2125 625);
DISPLAY INVISIBLE (2125 625);
FORCEPROP 2 LAST CDS_SEC 1
J 0
(2125 625);
DISPLAY 1.021277 (2125 625);
DISPLAY INVISIBLE (2125 625);
FORCEPROP 1 LAST PATH I188
J 0
(2125 575);
DISPLAY 0.978723 (2125 575);
PAINT WHITE (2125 575);
DISPLAY INVISIBLE (2125 575);
FORCEADD TAP..1
(-650 3600);
FORCEPROP 3 LASTPIN (-700 3600) SIG_NAME M_A_CPU0_SA_DQ<17>
J 0
(-690 3610);
DISPLAY 0.659574 (-690 3610);
PAINT MONO (-690 3610);
DISPLAY INVISIBLE (-690 3610);
FORCEPROP 1 LASTPIN (-700 3600) BN 17
J 0
(-712 3608);
DISPLAY 0.680851 (-712 3608);
PAINT GREEN (-712 3608);
FORCEPROP 2 LAST CDS_LIB standard
J 0
(-650 3600);
PAINT MONO (-650 3600);
DISPLAY INVISIBLE (-650 3600);
FORCEPROP 1 LAST BODY_TYPE PLUMBING
J 0
(-650 3650);
DISPLAY 0.872340 (-650 3650);
PAINT GREEN (-650 3650);
DISPLAY INVISIBLE (-650 3650);
FORCEPROP 1 LAST HDL_TAP TRUE
J 0
(-325 3475);
DISPLAY 0.872340 (-325 3475);
DISPLAY INVISIBLE (-325 3475);
FORCEPROP 1 LAST PATH I19
J 0
(-652 3600);
DISPLAY 0.872340 (-652 3600);
PAINT GREEN (-652 3600);
DISPLAY INVISIBLE (-652 3600);
FORCEADD Q_CAP..1
(2700 425);
FORCEPROP 1 LAST PART_NUMBER CH6103KEA00
J 0
(2750 275);
DISPLAY 0.978723 (2750 275);
DISPLAY INVISIBLE (2750 275);
FORCEPROP 1 LAST MATERIAL X6S
J 0
(2750 325);
DISPLAY 0.978723 (2750 325);
FORCEPROP 1 LAST PACK_TYPE C0805
J 0
(2750 225);
DISPLAY 0.978723 (2750 225);
FORCEPROP 1 LAST VOLTAGE 16V
J 0
(2750 425);
DISPLAY 0.978723 (2750 425);
FORCEPROP 1 LAST VALUE 10UF
J 0
(2750 475);
DISPLAY 0.978723 (2750 475);
FORCEPROP 1 LAST TOLERANCE 10%
J 0
(2750 375);
DISPLAY 0.978723 (2750 375);
FORCEPROP 1 LAST $LOCATION C4
J 0
(2750 525);
DISPLAY 0.978723 (2750 525);
FORCEPROP 1 LASTPIN (2700 525) $PN 1
J 0
(2710 505);
DISPLAY 0.787234 (2710 505);
FORCEPROP 1 LASTPIN (2700 325) $PN 2
J 0
(2710 305);
DISPLAY 0.787234 (2710 305);
FORCEPROP 2 LAST CDS_LIB pure_quanta
J 0
(2700 425);
PAINT MONO (2700 425);
DISPLAY INVISIBLE (2700 425);
FORCEPROP 2 LAST CDS_LOCATION C4
J 0
(2750 625);
DISPLAY 1.021277 (2750 625);
DISPLAY INVISIBLE (2750 625);
FORCEPROP 2 LAST $SEC 1
J 0
(2750 625);
DISPLAY 0.680851 (2750 625);
PAINT MONO (2750 625);
DISPLAY INVISIBLE (2750 625);
FORCEPROP 2 LAST CDS_SEC 1
J 0
(2750 625);
DISPLAY 1.021277 (2750 625);
DISPLAY INVISIBLE (2750 625);
FORCEPROP 1 LAST PATH I190
J 0
(2750 575);
DISPLAY 0.978723 (2750 575);
PAINT WHITE (2750 575);
DISPLAY INVISIBLE (2750 575);
FORCEADD UNIVERSAL_GND..1
(2700 50);
FORCEPROP 3 LASTPIN (2700 100) SIG_NAME GND\g
J 0
(2710 110);
DISPLAY 0.659574 (2710 110);
PAINT MONO (2710 110);
DISPLAY INVISIBLE (2710 110);
FORCEPROP 2 LAST CDS_LIB logical_power
J 0
(2700 50);
PAINT MONO (2700 50);
DISPLAY INVISIBLE (2700 50);
FORCEPROP 1 LAST HDL_POWER GND
J 1
(2725 -25);
DISPLAY 0.872340 (2725 -25);
PAINT GREEN (2725 -25);
DISPLAY INVISIBLE (2725 -25);
FORCEPROP 1 LAST PATH I191
J 0
(2775 50);
DISPLAY 0.872340 (2775 50);
PAINT AQUA (2775 50);
DISPLAY INVISIBLE (2775 50);
FORCEADD Q_CAP..1
(1075 425);
FORCEPROP 1 LAST PART_NUMBER CH5221MEB00
J 0
(1125 275);
DISPLAY 0.978723 (1125 275);
DISPLAY INVISIBLE (1125 275);
FORCEPROP 1 LAST MATERIAL X6S
J 0
(1125 325);
DISPLAY 0.978723 (1125 325);
FORCEPROP 1 LAST VOLTAGE 6.3V
J 0
(1125 425);
DISPLAY 0.978723 (1125 425);
FORCEPROP 1 LAST PACK_TYPE C0402
J 0
(1125 225);
DISPLAY 0.978723 (1125 225);
FORCEPROP 1 LAST VALUE 2.2UF
J 0
(1125 475);
DISPLAY 0.978723 (1125 475);
FORCEPROP 1 LAST TOLERANCE 20%
J 0
(1125 375);
DISPLAY 0.978723 (1125 375);
FORCEPROP 1 LAST $LOCATION C2
J 0
(1125 525);
DISPLAY 0.978723 (1125 525);
FORCEPROP 1 LASTPIN (1075 525) $PN 1
J 0
(1085 505);
DISPLAY 0.787234 (1085 505);
FORCEPROP 1 LASTPIN (1075 325) $PN 2
J 0
(1085 305);
DISPLAY 0.787234 (1085 305);
FORCEPROP 2 LAST CDS_LIB pure_quanta
J 0
(1075 425);
PAINT MONO (1075 425);
DISPLAY INVISIBLE (1075 425);
FORCEPROP 2 LAST CDS_LOCATION C2
J 0
(1125 625);
DISPLAY 1.021277 (1125 625);
DISPLAY INVISIBLE (1125 625);
FORCEPROP 2 LAST $SEC 1
J 0
(1125 625);
DISPLAY 0.680851 (1125 625);
PAINT MONO (1125 625);
DISPLAY INVISIBLE (1125 625);
FORCEPROP 2 LAST CDS_SEC 1
J 0
(1125 625);
DISPLAY 1.021277 (1125 625);
DISPLAY INVISIBLE (1125 625);
FORCEPROP 1 LAST PATH I192
J 0
(1125 575);
DISPLAY 0.978723 (1125 575);
PAINT WHITE (1125 575);
DISPLAY INVISIBLE (1125 575);
FORCEADD VCC_CORE..1
(1075 750);
FORCEPROP 3 LASTPIN (1075 700) SIG_NAME P3V3_AUX\g
J 0
(1085 710);
DISPLAY 0.659574 (1085 710);
PAINT MONO (1085 710);
DISPLAY INVISIBLE (1085 710);
FORCEPROP 1 LAST HDL_POWER P3V3_AUX
J 1
(1075 800);
DISPLAY 1.148936 (1075 800);
PAINT GREEN (1075 800);
FORCEPROP 2 LAST CDS_LIB logical_power
J 0
(1075 750);
PAINT MONO (1075 750);
DISPLAY INVISIBLE (1075 750);
FORCEPROP 1 LAST PATH I193
J 0
(1125 775);
DISPLAY 0.872340 (1125 775);
PAINT AQUA (1125 775);
DISPLAY INVISIBLE (1125 775);
FORCEADD UNIVERSAL_GND..1
(1075 50);
FORCEPROP 3 LASTPIN (1075 100) SIG_NAME GND\g
J 0
(1085 110);
DISPLAY 0.659574 (1085 110);
PAINT MONO (1085 110);
DISPLAY INVISIBLE (1085 110);
FORCEPROP 2 LAST CDS_LIB logical_power
J 0
(1075 50);
PAINT MONO (1075 50);
DISPLAY INVISIBLE (1075 50);
FORCEPROP 1 LAST HDL_POWER GND
J 1
(1100 -25);
DISPLAY 0.872340 (1100 -25);
PAINT GREEN (1100 -25);
DISPLAY INVISIBLE (1100 -25);
FORCEPROP 1 LAST PATH I194
J 0
(1150 50);
DISPLAY 0.872340 (1150 50);
PAINT AQUA (1150 50);
DISPLAY INVISIBLE (1150 50);
FORCEADD OFFPAGE..2
R 2
(-3225 350);
FORCEPROP 2 LAST $XR0 82 
J 0
(-3479 350);
DISPLAY 0.638298 (-3479 350);
PAINT MONO (-3479 350);
FORCEPROP 2 LAST CDS_LIB standard
J 0
(-3225 350);
PAINT MONO (-3225 350);
DISPLAY INVISIBLE (-3225 350);
FORCEPROP 1 LAST OFFPAGE TRUE
J 2
(-3550 225);
DISPLAY 0.872340 (-3550 225);
DISPLAY INVISIBLE (-3550 225);
FORCEPROP 1 LAST COMMENT_BODY TRUE
J 2
(-3180 255);
DISPLAY 0.872340 (-3180 255);
PAINT GREEN (-3180 255);
DISPLAY INVISIBLE (-3180 255);
FORCEPROP 2 LAST PATH I195
J 0
(-3175 425);
DISPLAY 1.021277 (-3175 425);
DISPLAY INVISIBLE (-3175 425);
FORCEADD Q_RES..2
(-2075 150);
FORCEPROP 1 LAST PART_NUMBER CS31002FB08
J 0
(-2035 25);
DISPLAY 0.978723 (-2035 25);
DISPLAY INVISIBLE (-2035 25);
FORCEPROP 1 LAST WATTAGE 1/16W
J 0
(-2035 125);
DISPLAY 0.978723 (-2035 125);
FORCEPROP 1 LAST MATERIAL CHIP
J 0
(-2035 75);
DISPLAY 0.978723 (-2035 75);
FORCEPROP 1 LAST TOLERANCE 1%
J 0
(-2030 175);
DISPLAY 0.978723 (-2030 175);
FORCEPROP 1 LAST VALUE 10K
J 0
(-2030 225);
DISPLAY 0.978723 (-2030 225);
FORCEPROP 1 LAST PACK_TYPE 0402LF
J 0
(-2035 -25);
DISPLAY 0.978723 (-2035 -25);
FORCEPROP 1 LAST $LOCATION R26
J 0
(-2030 275);
DISPLAY 0.978723 (-2030 275);
FORCEPROP 1 LASTPIN (-2075 250) $PN 1
J 0
(-2070 212);
DISPLAY 0.787234 (-2070 212);
FORCEPROP 1 LASTPIN (-2075 50) $PN 2
J 0
(-2070 60);
DISPLAY 0.787234 (-2070 60);
FORCEPROP 2 LAST CDS_LIB pure_quanta
J 0
(-2075 150);
PAINT MONO (-2075 150);
DISPLAY INVISIBLE (-2075 150);
FORCEPROP 2 LAST CDS_LOCATION R26
J 0
(-2025 375);
DISPLAY 1.021277 (-2025 375);
DISPLAY INVISIBLE (-2025 375);
FORCEPROP 2 LAST $SEC 1
J 0
(-2025 375);
DISPLAY 0.680851 (-2025 375);
PAINT MONO (-2025 375);
DISPLAY INVISIBLE (-2025 375);
FORCEPROP 2 LAST CDS_SEC 1
J 0
(-2025 375);
DISPLAY 1.021277 (-2025 375);
DISPLAY INVISIBLE (-2025 375);
FORCEPROP 1 LAST PATH I196
J 0
(-2025 325);
DISPLAY 0.978723 (-2025 325);
PAINT WHITE (-2025 325);
DISPLAY INVISIBLE (-2025 325);
FORCEADD UNIVERSAL_GND..1
(-2075 -75);
FORCEPROP 3 LASTPIN (-2075 -25) SIG_NAME GND\g
J 0
(-2065 -15);
DISPLAY 0.659574 (-2065 -15);
PAINT MONO (-2065 -15);
DISPLAY INVISIBLE (-2065 -15);
FORCEPROP 2 LAST CDS_LIB logical_power
J 0
(-2075 -75);
PAINT MONO (-2075 -75);
DISPLAY INVISIBLE (-2075 -75);
FORCEPROP 1 LAST HDL_POWER GND
J 1
(-2050 -150);
DISPLAY 0.872340 (-2050 -150);
PAINT GREEN (-2050 -150);
DISPLAY INVISIBLE (-2050 -150);
FORCEPROP 1 LAST PATH I197
J 0
(-2000 -75);
DISPLAY 0.872340 (-2000 -75);
PAINT AQUA (-2000 -75);
DISPLAY INVISIBLE (-2000 -75);
FORCEADD SCONN288_ADR50017P130CC..1
(-1475 2575);
FORCEPROP 1 LAST PART_NUMBER DFHST8FS461
J 0
(-1920 4597);
DISPLAY 0.723404 (-1920 4597);
PAINT GREEN (-1920 4597);
DISPLAY INVISIBLE (-1920 4597);
FORCEPROP 2 LAST VALUE SCONN288_ADR50017-P130CC
J 0
(-1925 4700);
DISPLAY 1.021277 (-1925 4700);
FORCEPROP 1 LAST MATERIAL IO
J 0
(-1920 4470);
DISPLAY 0.723404 (-1920 4470);
PAINT GREEN (-1920 4470);
FORCEPROP 2 LAST PART_TYPE SMLF
J 0
(-1925 4750);
DISPLAY 1.021277 (-1925 4750);
FORCEPROP 1 LAST $LOCATION J1
J 0
(-1925 4650);
DISPLAY 0.723404 (-1925 4650);
PAINT GREEN (-1925 4650);
FORCEPROP 0 LASTPIN (-2075 1950) $PN 62
J 2
(-2085 1960);
DISPLAY 0.680851 (-2085 1960);
PAINT MONO (-2085 1960);
FORCEPROP 0 LASTPIN (-2075 4000) $PN 66
J 2
(-2085 4010);
DISPLAY 0.680851 (-2085 4010);
PAINT MONO (-2085 4010);
FORCEPROP 0 LASTPIN (-2075 3600) $PN 76
J 2
(-2085 3610);
DISPLAY 0.680851 (-2085 3610);
PAINT MONO (-2085 3610);
FORCEPROP 0 LASTPIN (-2075 4050) $PN 211
J 2
(-2085 4060);
DISPLAY 0.680851 (-2085 4060);
PAINT MONO (-2085 4060);
FORCEPROP 0 LASTPIN (-2075 3650) $PN 221
J 2
(-2085 3660);
DISPLAY 0.680851 (-2085 3660);
PAINT MONO (-2085 3660);
FORCEPROP 0 LASTPIN (-2075 4100) $PN 68
J 2
(-2085 4110);
DISPLAY 0.680851 (-2085 4110);
PAINT MONO (-2085 4110);
FORCEPROP 0 LASTPIN (-2075 3700) $PN 78
J 2
(-2085 3710);
DISPLAY 0.680851 (-2085 3710);
PAINT MONO (-2085 3710);
FORCEPROP 0 LASTPIN (-2075 4150) $PN 213
J 2
(-2085 4160);
DISPLAY 0.680851 (-2085 4160);
PAINT MONO (-2085 4160);
FORCEPROP 0 LASTPIN (-2075 3750) $PN 223
J 2
(-2085 3760);
DISPLAY 0.680851 (-2085 3760);
PAINT MONO (-2085 3760);
FORCEPROP 0 LASTPIN (-2075 4200) $PN 70
J 2
(-2085 4210);
DISPLAY 0.680851 (-2085 4210);
PAINT MONO (-2085 4210);
FORCEPROP 0 LASTPIN (-2075 3800) $PN 80
J 2
(-2085 3810);
DISPLAY 0.680851 (-2085 3810);
PAINT MONO (-2085 3810);
FORCEPROP 0 LASTPIN (-2075 4250) $PN 215
J 2
(-2085 4260);
DISPLAY 0.680851 (-2085 4260);
PAINT MONO (-2085 4260);
FORCEPROP 0 LASTPIN (-2075 3850) $PN 225
J 2
(-2085 3860);
DISPLAY 0.680851 (-2085 3860);
PAINT MONO (-2085 3860);
FORCEPROP 0 LASTPIN (-2075 4300) $PN 72
J 2
(-2085 4310);
DISPLAY 0.680851 (-2085 4310);
PAINT MONO (-2085 4310);
FORCEPROP 0 LASTPIN (-2075 3900) $PN 82
J 2
(-2085 3910);
DISPLAY 0.680851 (-2085 3910);
PAINT MONO (-2085 3910);
FORCEPROP 0 LASTPIN (-2075 2550) $PN 51
J 2
(-2085 2560);
DISPLAY 0.680851 (-2085 2560);
PAINT MONO (-2085 2560);
FORCEPROP 0 LASTPIN (-2075 2100) $PN 96
J 2
(-2085 2110);
DISPLAY 0.680851 (-2085 2110);
PAINT MONO (-2085 2110);
FORCEPROP 0 LASTPIN (-2075 2600) $PN 53
J 2
(-2085 2610);
DISPLAY 0.680851 (-2085 2610);
PAINT MONO (-2085 2610);
FORCEPROP 0 LASTPIN (-2075 2150) $PN 98
J 2
(-2085 2160);
DISPLAY 0.680851 (-2085 2160);
PAINT MONO (-2085 2160);
FORCEPROP 0 LASTPIN (-2075 2650) $PN 196
J 2
(-2085 2660);
DISPLAY 0.680851 (-2085 2660);
PAINT MONO (-2085 2660);
FORCEPROP 0 LASTPIN (-2075 2200) $PN 241
J 2
(-2085 2210);
DISPLAY 0.680851 (-2085 2210);
PAINT MONO (-2085 2210);
FORCEPROP 0 LASTPIN (-2075 2700) $PN 198
J 2
(-2085 2710);
DISPLAY 0.680851 (-2085 2710);
PAINT MONO (-2085 2710);
FORCEPROP 0 LASTPIN (-2075 2250) $PN 243
J 2
(-2085 2260);
DISPLAY 0.680851 (-2085 2260);
PAINT MONO (-2085 2260);
FORCEPROP 0 LASTPIN (-2075 2750) $PN 58
J 2
(-2085 2760);
DISPLAY 0.680851 (-2085 2760);
PAINT MONO (-2085 2760);
FORCEPROP 0 LASTPIN (-2075 2300) $PN 89
J 2
(-2085 2310);
DISPLAY 0.680851 (-2085 2310);
PAINT MONO (-2085 2310);
FORCEPROP 0 LASTPIN (-2075 2800) $PN 60
J 2
(-2085 2810);
DISPLAY 0.680851 (-2085 2810);
PAINT MONO (-2085 2810);
FORCEPROP 0 LASTPIN (-2075 2350) $PN 91
J 2
(-2085 2360);
DISPLAY 0.680851 (-2085 2360);
PAINT MONO (-2085 2360);
FORCEPROP 0 LASTPIN (-2075 2850) $PN 203
J 2
(-2085 2860);
DISPLAY 0.680851 (-2085 2860);
PAINT MONO (-2085 2860);
FORCEPROP 0 LASTPIN (-2075 2400) $PN 234
J 2
(-2085 2410);
DISPLAY 0.680851 (-2085 2410);
PAINT MONO (-2085 2410);
FORCEPROP 0 LASTPIN (-2075 2900) $PN 205
J 2
(-2085 2910);
DISPLAY 0.680851 (-2085 2910);
PAINT MONO (-2085 2910);
FORCEPROP 0 LASTPIN (-2075 2450) $PN 236
J 2
(-2085 2460);
DISPLAY 0.680851 (-2085 2460);
PAINT MONO (-2085 2460);
FORCEPROP 0 LASTPIN (-2075 3000) $PN 218
J 2
(-2085 3010);
DISPLAY 0.680851 (-2085 3010);
PAINT MONO (-2085 3010);
FORCEPROP 0 LASTPIN (-2075 3050) $PN 217
J 2
(-2085 3060);
DISPLAY 0.680851 (-2085 3060);
PAINT MONO (-2085 3060);
FORCEPROP 0 LASTPIN (-2075 3300) $PN 64
J 2
(-2085 3310);
DISPLAY 0.680851 (-2085 3310);
PAINT MONO (-2085 3310);
FORCEPROP 0 LASTPIN (-2075 3150) $PN 84
J 2
(-2085 3160);
DISPLAY 0.680851 (-2085 3160);
PAINT MONO (-2085 3160);
FORCEPROP 0 LASTPIN (-2075 3350) $PN 209
J 2
(-2085 3360);
DISPLAY 0.680851 (-2085 3360);
PAINT MONO (-2085 3360);
FORCEPROP 0 LASTPIN (-2075 3200) $PN 229
J 2
(-2085 3210);
DISPLAY 0.680851 (-2085 3210);
PAINT MONO (-2085 3210);
FORCEPROP 0 LASTPIN (-875 2750) $PN 7
J 0
(-865 2760);
DISPLAY 0.680851 (-865 2760);
PAINT MONO (-865 2760);
FORCEPROP 0 LASTPIN (-875 1100) $PN 100
J 0
(-865 1110);
DISPLAY 0.680851 (-865 1110);
PAINT MONO (-865 1110);
FORCEPROP 0 LASTPIN (-875 2800) $PN 9
J 0
(-865 2810);
DISPLAY 0.680851 (-865 2810);
PAINT MONO (-865 2810);
FORCEPROP 0 LASTPIN (-875 1150) $PN 102
J 0
(-865 1160);
DISPLAY 0.680851 (-865 1160);
PAINT MONO (-865 1160);
FORCEPROP 0 LASTPIN (-875 2850) $PN 152
J 0
(-865 2860);
DISPLAY 0.680851 (-865 2860);
PAINT MONO (-865 2860);
FORCEPROP 0 LASTPIN (-875 1200) $PN 245
J 0
(-865 1210);
DISPLAY 0.680851 (-865 1210);
PAINT MONO (-865 1210);
FORCEPROP 0 LASTPIN (-875 2900) $PN 154
J 0
(-865 2910);
DISPLAY 0.680851 (-865 2910);
PAINT MONO (-865 2910);
FORCEPROP 0 LASTPIN (-875 1250) $PN 247
J 0
(-865 1260);
DISPLAY 0.680851 (-865 1260);
PAINT MONO (-865 1260);
FORCEPROP 0 LASTPIN (-875 2950) $PN 14
J 0
(-865 2960);
DISPLAY 0.680851 (-865 2960);
PAINT MONO (-865 2960);
FORCEPROP 0 LASTPIN (-875 1300) $PN 107
J 0
(-865 1310);
DISPLAY 0.680851 (-865 1310);
PAINT MONO (-865 1310);
FORCEPROP 0 LASTPIN (-875 3000) $PN 16
J 0
(-865 3010);
DISPLAY 0.680851 (-865 3010);
PAINT MONO (-865 3010);
FORCEPROP 0 LASTPIN (-875 1350) $PN 109
J 0
(-865 1360);
DISPLAY 0.680851 (-865 1360);
PAINT MONO (-865 1360);
FORCEPROP 0 LASTPIN (-875 3050) $PN 159
J 0
(-865 3060);
DISPLAY 0.680851 (-865 3060);
PAINT MONO (-865 3060);
FORCEPROP 0 LASTPIN (-875 1400) $PN 252
J 0
(-865 1410);
DISPLAY 0.680851 (-865 1410);
PAINT MONO (-865 1410);
FORCEPROP 0 LASTPIN (-875 3100) $PN 161
J 0
(-865 3110);
DISPLAY 0.680851 (-865 3110);
PAINT MONO (-865 3110);
FORCEPROP 0 LASTPIN (-875 1450) $PN 254
J 0
(-865 1460);
DISPLAY 0.680851 (-865 1460);
PAINT MONO (-865 1460);
FORCEPROP 0 LASTPIN (-875 3150) $PN 18
J 0
(-865 3160);
DISPLAY 0.680851 (-865 3160);
PAINT MONO (-865 3160);
FORCEPROP 0 LASTPIN (-875 1500) $PN 111
J 0
(-865 1510);
DISPLAY 0.680851 (-865 1510);
PAINT MONO (-865 1510);
FORCEPROP 0 LASTPIN (-875 3200) $PN 20
J 0
(-865 3210);
DISPLAY 0.680851 (-865 3210);
PAINT MONO (-865 3210);
FORCEPROP 0 LASTPIN (-875 1550) $PN 113
J 0
(-865 1560);
DISPLAY 0.680851 (-865 1560);
PAINT MONO (-865 1560);
FORCEPROP 0 LASTPIN (-875 3250) $PN 163
J 0
(-865 3260);
DISPLAY 0.680851 (-865 3260);
PAINT MONO (-865 3260);
FORCEPROP 0 LASTPIN (-875 1600) $PN 256
J 0
(-865 1610);
DISPLAY 0.680851 (-865 1610);
PAINT MONO (-865 1610);
FORCEPROP 0 LASTPIN (-875 3300) $PN 165
J 0
(-865 3310);
DISPLAY 0.680851 (-865 3310);
PAINT MONO (-865 3310);
FORCEPROP 0 LASTPIN (-875 1650) $PN 258
J 0
(-865 1660);
DISPLAY 0.680851 (-865 1660);
PAINT MONO (-865 1660);
FORCEPROP 0 LASTPIN (-875 3350) $PN 25
J 0
(-865 3360);
DISPLAY 0.680851 (-865 3360);
PAINT MONO (-865 3360);
FORCEPROP 0 LASTPIN (-875 1700) $PN 118
J 0
(-865 1710);
DISPLAY 0.680851 (-865 1710);
PAINT MONO (-865 1710);
FORCEPROP 0 LASTPIN (-875 3400) $PN 27
J 0
(-865 3410);
DISPLAY 0.680851 (-865 3410);
PAINT MONO (-865 3410);
FORCEPROP 0 LASTPIN (-875 1750) $PN 120
J 0
(-865 1760);
DISPLAY 0.680851 (-865 1760);
PAINT MONO (-865 1760);
FORCEPROP 0 LASTPIN (-875 3450) $PN 170
J 0
(-865 3460);
DISPLAY 0.680851 (-865 3460);
PAINT MONO (-865 3460);
FORCEPROP 0 LASTPIN (-875 1800) $PN 263
J 0
(-865 1810);
DISPLAY 0.680851 (-865 1810);
PAINT MONO (-865 1810);
FORCEPROP 0 LASTPIN (-875 3500) $PN 172
J 0
(-865 3510);
DISPLAY 0.680851 (-865 3510);
PAINT MONO (-865 3510);
FORCEPROP 0 LASTPIN (-875 1850) $PN 265
J 0
(-865 1860);
DISPLAY 0.680851 (-865 1860);
PAINT MONO (-865 1860);
FORCEPROP 0 LASTPIN (-875 3550) $PN 29
J 0
(-865 3560);
DISPLAY 0.680851 (-865 3560);
PAINT MONO (-865 3560);
FORCEPROP 0 LASTPIN (-875 1900) $PN 122
J 0
(-865 1910);
DISPLAY 0.680851 (-865 1910);
PAINT MONO (-865 1910);
FORCEPROP 0 LASTPIN (-875 3600) $PN 31
J 0
(-865 3610);
DISPLAY 0.680851 (-865 3610);
PAINT MONO (-865 3610);
FORCEPROP 0 LASTPIN (-875 1950) $PN 124
J 0
(-865 1960);
DISPLAY 0.680851 (-865 1960);
PAINT MONO (-865 1960);
FORCEPROP 0 LASTPIN (-875 3650) $PN 174
J 0
(-865 3660);
DISPLAY 0.680851 (-865 3660);
PAINT MONO (-865 3660);
FORCEPROP 0 LASTPIN (-875 2000) $PN 267
J 0
(-865 2010);
DISPLAY 0.680851 (-865 2010);
PAINT MONO (-865 2010);
FORCEPROP 0 LASTPIN (-875 3700) $PN 176
J 0
(-865 3710);
DISPLAY 0.680851 (-865 3710);
PAINT MONO (-865 3710);
FORCEPROP 0 LASTPIN (-875 2050) $PN 269
J 0
(-865 2060);
DISPLAY 0.680851 (-865 2060);
PAINT MONO (-865 2060);
FORCEPROP 0 LASTPIN (-875 3750) $PN 36
J 0
(-865 3760);
DISPLAY 0.680851 (-865 3760);
PAINT MONO (-865 3760);
FORCEPROP 0 LASTPIN (-875 2100) $PN 129
J 0
(-865 2110);
DISPLAY 0.680851 (-865 2110);
PAINT MONO (-865 2110);
FORCEPROP 0 LASTPIN (-875 3800) $PN 38
J 0
(-865 3810);
DISPLAY 0.680851 (-865 3810);
PAINT MONO (-865 3810);
FORCEPROP 0 LASTPIN (-875 2150) $PN 131
J 0
(-865 2160);
DISPLAY 0.680851 (-865 2160);
PAINT MONO (-865 2160);
FORCEPROP 0 LASTPIN (-875 3850) $PN 181
J 0
(-865 3860);
DISPLAY 0.680851 (-865 3860);
PAINT MONO (-865 3860);
FORCEPROP 0 LASTPIN (-875 2200) $PN 274
J 0
(-865 2210);
DISPLAY 0.680851 (-865 2210);
PAINT MONO (-865 2210);
FORCEPROP 0 LASTPIN (-875 3900) $PN 183
J 0
(-865 3910);
DISPLAY 0.680851 (-865 3910);
PAINT MONO (-865 3910);
FORCEPROP 0 LASTPIN (-875 2250) $PN 276
J 0
(-865 2260);
DISPLAY 0.680851 (-865 2260);
PAINT MONO (-865 2260);
FORCEPROP 0 LASTPIN (-875 3950) $PN 40
J 0
(-865 3960);
DISPLAY 0.680851 (-865 3960);
PAINT MONO (-865 3960);
FORCEPROP 0 LASTPIN (-875 2300) $PN 133
J 0
(-865 2310);
DISPLAY 0.680851 (-865 2310);
PAINT MONO (-865 2310);
FORCEPROP 0 LASTPIN (-875 4000) $PN 42
J 0
(-865 4010);
DISPLAY 0.680851 (-865 4010);
PAINT MONO (-865 4010);
FORCEPROP 0 LASTPIN (-875 2350) $PN 135
J 0
(-865 2360);
DISPLAY 0.680851 (-865 2360);
PAINT MONO (-865 2360);
FORCEPROP 0 LASTPIN (-875 4050) $PN 185
J 0
(-865 4060);
DISPLAY 0.680851 (-865 4060);
PAINT MONO (-865 4060);
FORCEPROP 0 LASTPIN (-875 2400) $PN 278
J 0
(-865 2410);
DISPLAY 0.680851 (-865 2410);
PAINT MONO (-865 2410);
FORCEPROP 0 LASTPIN (-875 4100) $PN 187
J 0
(-865 4110);
DISPLAY 0.680851 (-865 4110);
PAINT MONO (-865 4110);
FORCEPROP 0 LASTPIN (-875 2450) $PN 280
J 0
(-865 2460);
DISPLAY 0.680851 (-865 2460);
PAINT MONO (-865 2460);
FORCEPROP 0 LASTPIN (-875 4150) $PN 47
J 0
(-865 4160);
DISPLAY 0.680851 (-865 4160);
PAINT MONO (-865 4160);
FORCEPROP 0 LASTPIN (-875 2500) $PN 140
J 0
(-865 2510);
DISPLAY 0.680851 (-865 2510);
PAINT MONO (-865 2510);
FORCEPROP 0 LASTPIN (-875 4200) $PN 49
J 0
(-865 4210);
DISPLAY 0.680851 (-865 4210);
PAINT MONO (-865 4210);
FORCEPROP 0 LASTPIN (-875 2550) $PN 142
J 0
(-865 2560);
DISPLAY 0.680851 (-865 2560);
PAINT MONO (-865 2560);
FORCEPROP 0 LASTPIN (-875 4250) $PN 192
J 0
(-865 4260);
DISPLAY 0.680851 (-865 4260);
PAINT MONO (-865 4260);
FORCEPROP 0 LASTPIN (-875 2600) $PN 285
J 0
(-865 2610);
DISPLAY 0.680851 (-865 2610);
PAINT MONO (-865 2610);
FORCEPROP 0 LASTPIN (-875 4300) $PN 194
J 0
(-865 4310);
DISPLAY 0.680851 (-865 4310);
PAINT MONO (-865 4310);
FORCEPROP 0 LASTPIN (-875 2650) $PN 287
J 0
(-865 2660);
DISPLAY 0.680851 (-865 2660);
PAINT MONO (-865 2660);
FORCEPROP 0 LASTPIN (-2075 1800) $PN 148
J 2
(-2085 1810);
DISPLAY 0.680851 (-2085 1810);
PAINT MONO (-2085 1810);
FORCEPROP 0 LASTPIN (-2075 1700) $PN 4
J 2
(-2085 1710);
DISPLAY 0.680851 (-2085 1710);
PAINT MONO (-2085 1710);
FORCEPROP 0 LASTPIN (-2075 1750) $PN 5
J 2
(-2085 1760);
DISPLAY 0.680851 (-2085 1760);
PAINT MONO (-2085 1760);
FORCEPROP 0 LASTPIN (-2075 900) $PN 86
J 2
(-2085 910);
DISPLAY 0.680851 (-2085 910);
PAINT MONO (-2085 910);
FORCEPROP 0 LASTPIN (-2075 850) $PN 87
J 2
(-2085 860);
DISPLAY 0.680851 (-2085 860);
PAINT MONO (-2085 860);
FORCEPROP 0 LASTPIN (-2075 3500) $PN 74
J 2
(-2085 3510);
DISPLAY 0.680851 (-2085 3510);
PAINT MONO (-2085 3510);
FORCEPROP 0 LASTPIN (-2075 3450) $PN 227
J 2
(-2085 3460);
DISPLAY 0.680851 (-2085 3460);
PAINT MONO (-2085 3460);
FORCEPROP 0 LASTPIN (-2075 1450) $PN 147
J 2
(-2085 1460);
DISPLAY 0.680851 (-2085 1460);
PAINT MONO (-2085 1460);
FORCEPROP 0 LASTPIN (-2075 2000) $PN 207
J 2
(-2085 2010);
DISPLAY 0.680851 (-2085 2010);
PAINT MONO (-2085 2010);
FORCEPROP 0 LASTPIN (-2075 1050) $PN 2
J 2
(-2085 1060);
DISPLAY 0.680851 (-2085 1060);
PAINT MONO (-2085 1060);
FORCEPROP 0 LASTPIN (-2075 1100) $PN 144
J 2
(-2085 1110);
DISPLAY 0.680851 (-2085 1110);
PAINT MONO (-2085 1110);
FORCEPROP 0 LASTPIN (-2075 1150) $PN 149
J 2
(-2085 1160);
DISPLAY 0.680851 (-2085 1160);
PAINT MONO (-2085 1160);
FORCEPROP 0 LASTPIN (-2075 1200) $PN 150
J 2
(-2085 1210);
DISPLAY 0.680851 (-2085 1210);
PAINT MONO (-2085 1210);
FORCEPROP 0 LASTPIN (-2075 1250) $PN 220
J 2
(-2085 1260);
DISPLAY 0.680851 (-2085 1260);
PAINT MONO (-2085 1260);
FORCEPROP 0 LASTPIN (-2075 1300) $PN 231
J 2
(-2085 1310);
DISPLAY 0.680851 (-2085 1310);
PAINT MONO (-2085 1310);
FORCEPROP 0 LASTPIN (-2075 1350) $PN 232
J 2
(-2085 1360);
DISPLAY 0.680851 (-2085 1360);
PAINT MONO (-2085 1360);
FORCEPROP 0 LASTPIN (-2075 1850) $PN 3
J 2
(-2085 1860);
DISPLAY 0.680851 (-2085 1860);
PAINT MONO (-2085 1860);
FORCEPROP 2 LAST CDS_LIB pure_quanta
J 0
(-1475 2575);
DISPLAY INVISIBLE (-1475 2575);
FORCEPROP 1 LAST CDS_LMAN_SYM_OUTLINE -450,1875,450,-1875
J 0
(-1475 2575);
DISPLAY 0.468085 (-1475 2575);
PAINT GREEN (-1475 2575);
DISPLAY INVISIBLE (-1475 2575);
FORCEPROP 1 LAST NEEDS_NO_SIZE TRUE
J 0
(-1475 2575);
DISPLAY 0.723404 (-1475 2575);
PAINT GREEN (-1475 2575);
DISPLAY INVISIBLE (-1475 2575);
FORCEPROP 2 LAST CDS_LOCATION J1
J 0
(850 4800);
DISPLAY 1.021277 (850 4800);
DISPLAY INVISIBLE (850 4800);
FORCEPROP 0 LAST $SEC 1
J 0
(-1900 4800);
DISPLAY 0.680851 (-1900 4800);
PAINT MONO (-1900 4800);
DISPLAY INVISIBLE (-1900 4800);
FORCEPROP 2 LAST CDS_SEC 1
J 0
(-1925 4800);
DISPLAY 1.021277 (-1925 4800);
DISPLAY INVISIBLE (-1925 4800);
FORCEPROP 1 LAST PATH I198
J 0
(-1475 2575);
DISPLAY 0.723404 (-1475 2575);
PAINT GREEN (-1475 2575);
DISPLAY INVISIBLE (-1475 2575);
FORCEADD TAP..1
(-650 3550);
FORCEPROP 3 LASTPIN (-700 3550) SIG_NAME M_A_CPU0_SA_DQ<16>
J 0
(-690 3560);
DISPLAY 0.659574 (-690 3560);
PAINT MONO (-690 3560);
DISPLAY INVISIBLE (-690 3560);
FORCEPROP 1 LASTPIN (-700 3550) BN 16
J 0
(-712 3558);
DISPLAY 0.680851 (-712 3558);
PAINT GREEN (-712 3558);
FORCEPROP 2 LAST CDS_LIB standard
J 0
(-650 3550);
PAINT MONO (-650 3550);
DISPLAY INVISIBLE (-650 3550);
FORCEPROP 1 LAST BODY_TYPE PLUMBING
J 0
(-650 3600);
DISPLAY 0.872340 (-650 3600);
PAINT GREEN (-650 3600);
DISPLAY INVISIBLE (-650 3600);
FORCEPROP 1 LAST HDL_TAP TRUE
J 0
(-325 3425);
DISPLAY 0.872340 (-325 3425);
DISPLAY INVISIBLE (-325 3425);
FORCEPROP 1 LAST PATH I20
J 0
(-652 3550);
DISPLAY 0.872340 (-652 3550);
PAINT GREEN (-652 3550);
DISPLAY INVISIBLE (-652 3550);
FORCEADD OFFPAGE..3
R 2
(-3225 1450);
FORCEPROP 2 LAST $XR0 114 
J 0
(-3505 1450);
DISPLAY 0.638298 (-3505 1450);
PAINT MONO (-3505 1450);
FORCEPROP 2 LAST CDS_LIB standard
J 0
(-3225 1450);
PAINT MONO (-3225 1450);
DISPLAY INVISIBLE (-3225 1450);
FORCEPROP 1 LAST OFFPAGE TRUE
J 2
(-3550 1325);
DISPLAY 0.872340 (-3550 1325);
DISPLAY INVISIBLE (-3550 1325);
FORCEPROP 1 LAST COMMENT_BODY TRUE
J 2
(-3175 1350);
DISPLAY 0.872340 (-3175 1350);
PAINT GREEN (-3175 1350);
DISPLAY INVISIBLE (-3175 1350);
FORCEPROP 2 LAST PATH I201
J 0
(-3175 1525);
DISPLAY 1.021277 (-3175 1525);
DISPLAY INVISIBLE (-3175 1525);
FORCEADD SCONN288_ADR50017P130CC..2
(1300 3300);
FORCEPROP 1 LAST PART_NUMBER DFHST8FS461
J 0
(707 4600);
DISPLAY 0.723404 (707 4600);
PAINT GREEN (707 4600);
DISPLAY INVISIBLE (707 4600);
FORCEPROP 1 LAST MATERIAL IO
J 0
(707 4473);
DISPLAY 0.723404 (707 4473);
PAINT GREEN (707 4473);
FORCEPROP 2 LAST PART_TYPE SMLF
J 0
(725 4850);
DISPLAY 1.021277 (725 4850);
FORCEPROP 2 LAST VALUE SCONN288_ADR50017-P130CC
J 0
(725 4800);
DISPLAY 1.021277 (725 4800);
FORCEPROP 1 LAST LOCATION J1
J 0
(707 4747);
DISPLAY 0.723404 (707 4747);
PAINT GREEN (707 4747);
FORCEPROP 0 LASTPIN (2050 3350) $PN 12
J 0
(2060 3360);
DISPLAY 0.680851 (2060 3360);
PAINT MONO (2060 3360);
FORCEPROP 0 LASTPIN (2050 3400) $PN 11
J 0
(2060 3410);
DISPLAY 0.680851 (2060 3410);
PAINT MONO (2060 3410);
FORCEPROP 0 LASTPIN (2050 2300) $PN 105
J 0
(2060 2310);
DISPLAY 0.680851 (2060 2310);
PAINT MONO (2060 2310);
FORCEPROP 0 LASTPIN (2050 2350) $PN 104
J 0
(2060 2360);
DISPLAY 0.680851 (2060 2360);
PAINT MONO (2060 2360);
FORCEPROP 0 LASTPIN (2050 3450) $PN 23
J 0
(2060 3460);
DISPLAY 0.680851 (2060 3460);
PAINT MONO (2060 3460);
FORCEPROP 0 LASTPIN (2050 3500) $PN 22
J 0
(2060 3510);
DISPLAY 0.680851 (2060 3510);
PAINT MONO (2060 3510);
FORCEPROP 0 LASTPIN (2050 2400) $PN 116
J 0
(2060 2410);
DISPLAY 0.680851 (2060 2410);
PAINT MONO (2060 2410);
FORCEPROP 0 LASTPIN (2050 2450) $PN 115
J 0
(2060 2460);
DISPLAY 0.680851 (2060 2460);
PAINT MONO (2060 2460);
FORCEPROP 0 LASTPIN (2050 3550) $PN 34
J 0
(2060 3560);
DISPLAY 0.680851 (2060 3560);
PAINT MONO (2060 3560);
FORCEPROP 0 LASTPIN (2050 3600) $PN 33
J 0
(2060 3610);
DISPLAY 0.680851 (2060 3610);
PAINT MONO (2060 3610);
FORCEPROP 0 LASTPIN (2050 2500) $PN 127
J 0
(2060 2510);
DISPLAY 0.680851 (2060 2510);
PAINT MONO (2060 2510);
FORCEPROP 0 LASTPIN (2050 2550) $PN 126
J 0
(2060 2560);
DISPLAY 0.680851 (2060 2560);
PAINT MONO (2060 2560);
FORCEPROP 0 LASTPIN (2050 3650) $PN 45
J 0
(2060 3660);
DISPLAY 0.680851 (2060 3660);
PAINT MONO (2060 3660);
FORCEPROP 0 LASTPIN (2050 3700) $PN 44
J 0
(2060 3710);
DISPLAY 0.680851 (2060 3710);
PAINT MONO (2060 3710);
FORCEPROP 0 LASTPIN (2050 2600) $PN 138
J 0
(2060 2610);
DISPLAY 0.680851 (2060 2610);
PAINT MONO (2060 2610);
FORCEPROP 0 LASTPIN (2050 2650) $PN 137
J 0
(2060 2660);
DISPLAY 0.680851 (2060 2660);
PAINT MONO (2060 2660);
FORCEPROP 0 LASTPIN (2050 3750) $PN 56
J 0
(2060 3760);
DISPLAY 0.680851 (2060 3760);
PAINT MONO (2060 3760);
FORCEPROP 0 LASTPIN (2050 3800) $PN 55
J 0
(2060 3810);
DISPLAY 0.680851 (2060 3810);
PAINT MONO (2060 3810);
FORCEPROP 0 LASTPIN (2050 2700) $PN 238
J 0
(2060 2710);
DISPLAY 0.680851 (2060 2710);
PAINT MONO (2060 2710);
FORCEPROP 0 LASTPIN (2050 2750) $PN 239
J 0
(2060 2760);
DISPLAY 0.680851 (2060 2760);
PAINT MONO (2060 2760);
FORCEPROP 0 LASTPIN (2050 3850) $PN 156
J 0
(2060 3860);
DISPLAY 0.680851 (2060 3860);
PAINT MONO (2060 3860);
FORCEPROP 0 LASTPIN (2050 3900) $PN 157
J 0
(2060 3910);
DISPLAY 0.680851 (2060 3910);
PAINT MONO (2060 3910);
FORCEPROP 0 LASTPIN (2050 2800) $PN 249
J 0
(2060 2810);
DISPLAY 0.680851 (2060 2810);
PAINT MONO (2060 2810);
FORCEPROP 0 LASTPIN (2050 2850) $PN 250
J 0
(2060 2860);
DISPLAY 0.680851 (2060 2860);
PAINT MONO (2060 2860);
FORCEPROP 0 LASTPIN (2050 3950) $PN 167
J 0
(2060 3960);
DISPLAY 0.680851 (2060 3960);
PAINT MONO (2060 3960);
FORCEPROP 0 LASTPIN (2050 4000) $PN 168
J 0
(2060 4010);
DISPLAY 0.680851 (2060 4010);
PAINT MONO (2060 4010);
FORCEPROP 0 LASTPIN (2050 2900) $PN 260
J 0
(2060 2910);
DISPLAY 0.680851 (2060 2910);
PAINT MONO (2060 2910);
FORCEPROP 0 LASTPIN (2050 2950) $PN 261
J 0
(2060 2960);
DISPLAY 0.680851 (2060 2960);
PAINT MONO (2060 2960);
FORCEPROP 0 LASTPIN (2050 4050) $PN 178
J 0
(2060 4060);
DISPLAY 0.680851 (2060 4060);
PAINT MONO (2060 4060);
FORCEPROP 0 LASTPIN (2050 4100) $PN 179
J 0
(2060 4110);
DISPLAY 0.680851 (2060 4110);
PAINT MONO (2060 4110);
FORCEPROP 0 LASTPIN (2050 3000) $PN 271
J 0
(2060 3010);
DISPLAY 0.680851 (2060 3010);
PAINT MONO (2060 3010);
FORCEPROP 0 LASTPIN (2050 3050) $PN 272
J 0
(2060 3060);
DISPLAY 0.680851 (2060 3060);
PAINT MONO (2060 3060);
FORCEPROP 0 LASTPIN (2050 4150) $PN 189
J 0
(2060 4160);
DISPLAY 0.680851 (2060 4160);
PAINT MONO (2060 4160);
FORCEPROP 0 LASTPIN (2050 4200) $PN 190
J 0
(2060 4210);
DISPLAY 0.680851 (2060 4210);
PAINT MONO (2060 4210);
FORCEPROP 0 LASTPIN (2050 3100) $PN 282
J 0
(2060 3110);
DISPLAY 0.680851 (2060 3110);
PAINT MONO (2060 3110);
FORCEPROP 0 LASTPIN (2050 3150) $PN 283
J 0
(2060 3160);
DISPLAY 0.680851 (2060 3160);
PAINT MONO (2060 3160);
FORCEPROP 0 LASTPIN (2050 4250) $PN 200
J 0
(2060 4260);
DISPLAY 0.680851 (2060 4260);
PAINT MONO (2060 4260);
FORCEPROP 0 LASTPIN (2050 4300) $PN 201
J 0
(2060 4310);
DISPLAY 0.680851 (2060 4310);
PAINT MONO (2060 4310);
FORCEPROP 0 LASTPIN (2050 3200) $PN 94
J 0
(2060 3210);
DISPLAY 0.680851 (2060 3210);
PAINT MONO (2060 3210);
FORCEPROP 0 LASTPIN (2050 3250) $PN 93
J 0
(2060 3260);
DISPLAY 0.680851 (2060 3260);
PAINT MONO (2060 3260);
FORCEPROP 2 LAST CDS_LIB pure_quanta
J 0
(1300 3300);
DISPLAY INVISIBLE (1300 3300);
FORCEPROP 1 LAST CDS_LMAN_SYM_OUTLINE -600,1150,600,-1150
J 0
(1300 3300);
DISPLAY 0.468085 (1300 3300);
PAINT GREEN (1300 3300);
DISPLAY INVISIBLE (1300 3300);
FORCEPROP 1 LAST NEEDS_NO_SIZE TRUE
J 0
(1300 3300);
DISPLAY 0.723404 (1300 3300);
PAINT GREEN (1300 3300);
DISPLAY INVISIBLE (1300 3300);
FORCEPROP 0 LAST $SEC 2
J 0
(725 4900);
DISPLAY 0.680851 (725 4900);
PAINT MONO (725 4900);
DISPLAY INVISIBLE (725 4900);
FORCEPROP 0 LAST CDS_SEC 2
J 0
(725 4900);
DISPLAY 1.021277 (725 4900);
DISPLAY INVISIBLE (725 4900);
FORCEPROP 1 LAST PATH I202
J 0
(1300 3300);
DISPLAY 0.723404 (1300 3300);
PAINT GREEN (1300 3300);
DISPLAY INVISIBLE (1300 3300);
FORCEADD SCONN288_ADR50017P130CC..3
(4625 2675);
FORCEPROP 1 LAST PART_NUMBER DFHST8FS461
J 0
(4170 4599);
DISPLAY 0.723404 (4170 4599);
PAINT GREEN (4170 4599);
DISPLAY INVISIBLE (4170 4599);
FORCEPROP 2 LAST PART_TYPE SMLF
J 0
(4175 4850);
DISPLAY 1.021277 (4175 4850);
FORCEPROP 1 LAST MATERIAL IO
J 0
(4170 4472);
DISPLAY 0.723404 (4170 4472);
PAINT GREEN (4170 4472);
FORCEPROP 2 LAST VALUE SCONN288_ADR50017-P130CC
J 0
(4175 4800);
DISPLAY 1.021277 (4175 4800);
FORCEPROP 1 LAST LOCATION J1
J 0
(4170 4746);
DISPLAY 0.723404 (4170 4746);
PAINT GREEN (4170 4746);
FORCEPROP 0 LASTPIN (5225 1050) $PN G1
J 0
(5235 1060);
DISPLAY 0.680851 (5235 1060);
PAINT MONO (5235 1060);
FORCEPROP 0 LASTPIN (5225 1000) $PN G2
J 0
(5235 1010);
DISPLAY 0.680851 (5235 1010);
PAINT MONO (5235 1010);
FORCEPROP 0 LASTPIN (5225 950) $PN G3
J 0
(5235 960);
DISPLAY 0.680851 (5235 960);
PAINT MONO (5235 960);
FORCEPROP 0 LASTPIN (4025 4200) $PN 1
J 2
(4015 4210);
DISPLAY 0.680851 (4015 4210);
PAINT MONO (4015 4210);
FORCEPROP 0 LASTPIN (4025 4250) $PN 145
J 2
(4015 4260);
DISPLAY 0.680851 (4015 4260);
PAINT MONO (4015 4260);
FORCEPROP 0 LASTPIN (4025 4300) $PN 146
J 2
(4015 4310);
DISPLAY 0.680851 (4015 4310);
PAINT MONO (4015 4310);
FORCEPROP 0 LASTPIN (5225 1150) $PN 6
J 0
(5235 1160);
DISPLAY 0.680851 (5235 1160);
PAINT MONO (5235 1160);
FORCEPROP 0 LASTPIN (5225 1200) $PN 8
J 0
(5235 1210);
DISPLAY 0.680851 (5235 1210);
PAINT MONO (5235 1210);
FORCEPROP 0 LASTPIN (5225 1250) $PN 10
J 0
(5235 1260);
DISPLAY 0.680851 (5235 1260);
PAINT MONO (5235 1260);
FORCEPROP 0 LASTPIN (5225 1300) $PN 13
J 0
(5235 1310);
DISPLAY 0.680851 (5235 1310);
PAINT MONO (5235 1310);
FORCEPROP 0 LASTPIN (5225 1350) $PN 15
J 0
(5235 1360);
DISPLAY 0.680851 (5235 1360);
PAINT MONO (5235 1360);
FORCEPROP 0 LASTPIN (5225 1400) $PN 17
J 0
(5235 1410);
DISPLAY 0.680851 (5235 1410);
PAINT MONO (5235 1410);
FORCEPROP 0 LASTPIN (5225 1450) $PN 19
J 0
(5235 1460);
DISPLAY 0.680851 (5235 1460);
PAINT MONO (5235 1460);
FORCEPROP 0 LASTPIN (5225 1500) $PN 21
J 0
(5235 1510);
DISPLAY 0.680851 (5235 1510);
PAINT MONO (5235 1510);
FORCEPROP 0 LASTPIN (5225 1550) $PN 24
J 0
(5235 1560);
DISPLAY 0.680851 (5235 1560);
PAINT MONO (5235 1560);
FORCEPROP 0 LASTPIN (5225 1600) $PN 26
J 0
(5235 1610);
DISPLAY 0.680851 (5235 1610);
PAINT MONO (5235 1610);
FORCEPROP 0 LASTPIN (5225 1650) $PN 28
J 0
(5235 1660);
DISPLAY 0.680851 (5235 1660);
PAINT MONO (5235 1660);
FORCEPROP 0 LASTPIN (5225 1700) $PN 30
J 0
(5235 1710);
DISPLAY 0.680851 (5235 1710);
PAINT MONO (5235 1710);
FORCEPROP 0 LASTPIN (5225 1750) $PN 32
J 0
(5235 1760);
DISPLAY 0.680851 (5235 1760);
PAINT MONO (5235 1760);
FORCEPROP 0 LASTPIN (5225 1800) $PN 35
J 0
(5235 1810);
DISPLAY 0.680851 (5235 1810);
PAINT MONO (5235 1810);
FORCEPROP 0 LASTPIN (5225 1850) $PN 37
J 0
(5235 1860);
DISPLAY 0.680851 (5235 1860);
PAINT MONO (5235 1860);
FORCEPROP 0 LASTPIN (5225 1900) $PN 39
J 0
(5235 1910);
DISPLAY 0.680851 (5235 1910);
PAINT MONO (5235 1910);
FORCEPROP 0 LASTPIN (5225 1950) $PN 41
J 0
(5235 1960);
DISPLAY 0.680851 (5235 1960);
PAINT MONO (5235 1960);
FORCEPROP 0 LASTPIN (5225 2000) $PN 43
J 0
(5235 2010);
DISPLAY 0.680851 (5235 2010);
PAINT MONO (5235 2010);
FORCEPROP 0 LASTPIN (5225 2050) $PN 46
J 0
(5235 2060);
DISPLAY 0.680851 (5235 2060);
PAINT MONO (5235 2060);
FORCEPROP 0 LASTPIN (5225 2100) $PN 48
J 0
(5235 2110);
DISPLAY 0.680851 (5235 2110);
PAINT MONO (5235 2110);
FORCEPROP 0 LASTPIN (5225 2150) $PN 50
J 0
(5235 2160);
DISPLAY 0.680851 (5235 2160);
PAINT MONO (5235 2160);
FORCEPROP 0 LASTPIN (5225 2200) $PN 52
J 0
(5235 2210);
DISPLAY 0.680851 (5235 2210);
PAINT MONO (5235 2210);
FORCEPROP 0 LASTPIN (5225 2250) $PN 54
J 0
(5235 2260);
DISPLAY 0.680851 (5235 2260);
PAINT MONO (5235 2260);
FORCEPROP 0 LASTPIN (5225 2300) $PN 57
J 0
(5235 2310);
DISPLAY 0.680851 (5235 2310);
PAINT MONO (5235 2310);
FORCEPROP 0 LASTPIN (5225 2350) $PN 59
J 0
(5235 2360);
DISPLAY 0.680851 (5235 2360);
PAINT MONO (5235 2360);
FORCEPROP 0 LASTPIN (5225 2400) $PN 61
J 0
(5235 2410);
DISPLAY 0.680851 (5235 2410);
PAINT MONO (5235 2410);
FORCEPROP 0 LASTPIN (5225 2450) $PN 63
J 0
(5235 2460);
DISPLAY 0.680851 (5235 2460);
PAINT MONO (5235 2460);
FORCEPROP 0 LASTPIN (5225 2500) $PN 65
J 0
(5235 2510);
DISPLAY 0.680851 (5235 2510);
PAINT MONO (5235 2510);
FORCEPROP 0 LASTPIN (5225 2550) $PN 67
J 0
(5235 2560);
DISPLAY 0.680851 (5235 2560);
PAINT MONO (5235 2560);
FORCEPROP 0 LASTPIN (5225 2600) $PN 69
J 0
(5235 2610);
DISPLAY 0.680851 (5235 2610);
PAINT MONO (5235 2610);
FORCEPROP 0 LASTPIN (5225 2650) $PN 71
J 0
(5235 2660);
DISPLAY 0.680851 (5235 2660);
PAINT MONO (5235 2660);
FORCEPROP 0 LASTPIN (5225 2700) $PN 73
J 0
(5235 2710);
DISPLAY 0.680851 (5235 2710);
PAINT MONO (5235 2710);
FORCEPROP 0 LASTPIN (5225 2750) $PN 75
J 0
(5235 2760);
DISPLAY 0.680851 (5235 2760);
PAINT MONO (5235 2760);
FORCEPROP 0 LASTPIN (5225 2800) $PN 77
J 0
(5235 2810);
DISPLAY 0.680851 (5235 2810);
PAINT MONO (5235 2810);
FORCEPROP 0 LASTPIN (5225 2850) $PN 79
J 0
(5235 2860);
DISPLAY 0.680851 (5235 2860);
PAINT MONO (5235 2860);
FORCEPROP 0 LASTPIN (5225 2900) $PN 81
J 0
(5235 2910);
DISPLAY 0.680851 (5235 2910);
PAINT MONO (5235 2910);
FORCEPROP 0 LASTPIN (5225 2950) $PN 83
J 0
(5235 2960);
DISPLAY 0.680851 (5235 2960);
PAINT MONO (5235 2960);
FORCEPROP 0 LASTPIN (5225 3000) $PN 85
J 0
(5235 3010);
DISPLAY 0.680851 (5235 3010);
PAINT MONO (5235 3010);
FORCEPROP 0 LASTPIN (5225 3050) $PN 88
J 0
(5235 3060);
DISPLAY 0.680851 (5235 3060);
PAINT MONO (5235 3060);
FORCEPROP 0 LASTPIN (5225 3100) $PN 90
J 0
(5235 3110);
DISPLAY 0.680851 (5235 3110);
PAINT MONO (5235 3110);
FORCEPROP 0 LASTPIN (5225 3150) $PN 92
J 0
(5235 3160);
DISPLAY 0.680851 (5235 3160);
PAINT MONO (5235 3160);
FORCEPROP 0 LASTPIN (5225 3200) $PN 95
J 0
(5235 3210);
DISPLAY 0.680851 (5235 3210);
PAINT MONO (5235 3210);
FORCEPROP 0 LASTPIN (5225 3250) $PN 97
J 0
(5235 3260);
DISPLAY 0.680851 (5235 3260);
PAINT MONO (5235 3260);
FORCEPROP 0 LASTPIN (5225 3300) $PN 99
J 0
(5235 3310);
DISPLAY 0.680851 (5235 3310);
PAINT MONO (5235 3310);
FORCEPROP 0 LASTPIN (5225 3350) $PN 101
J 0
(5235 3360);
DISPLAY 0.680851 (5235 3360);
PAINT MONO (5235 3360);
FORCEPROP 0 LASTPIN (5225 3400) $PN 103
J 0
(5235 3410);
DISPLAY 0.680851 (5235 3410);
PAINT MONO (5235 3410);
FORCEPROP 0 LASTPIN (5225 3450) $PN 106
J 0
(5235 3460);
DISPLAY 0.680851 (5235 3460);
PAINT MONO (5235 3460);
FORCEPROP 0 LASTPIN (5225 3500) $PN 108
J 0
(5235 3510);
DISPLAY 0.680851 (5235 3510);
PAINT MONO (5235 3510);
FORCEPROP 0 LASTPIN (5225 3550) $PN 110
J 0
(5235 3560);
DISPLAY 0.680851 (5235 3560);
PAINT MONO (5235 3560);
FORCEPROP 0 LASTPIN (5225 3600) $PN 112
J 0
(5235 3610);
DISPLAY 0.680851 (5235 3610);
PAINT MONO (5235 3610);
FORCEPROP 0 LASTPIN (5225 3650) $PN 114
J 0
(5235 3660);
DISPLAY 0.680851 (5235 3660);
PAINT MONO (5235 3660);
FORCEPROP 0 LASTPIN (5225 3700) $PN 117
J 0
(5235 3710);
DISPLAY 0.680851 (5235 3710);
PAINT MONO (5235 3710);
FORCEPROP 0 LASTPIN (5225 3750) $PN 119
J 0
(5235 3760);
DISPLAY 0.680851 (5235 3760);
PAINT MONO (5235 3760);
FORCEPROP 0 LASTPIN (5225 3800) $PN 121
J 0
(5235 3810);
DISPLAY 0.680851 (5235 3810);
PAINT MONO (5235 3810);
FORCEPROP 0 LASTPIN (5225 3850) $PN 123
J 0
(5235 3860);
DISPLAY 0.680851 (5235 3860);
PAINT MONO (5235 3860);
FORCEPROP 0 LASTPIN (5225 3900) $PN 125
J 0
(5235 3910);
DISPLAY 0.680851 (5235 3910);
PAINT MONO (5235 3910);
FORCEPROP 0 LASTPIN (5225 3950) $PN 128
J 0
(5235 3960);
DISPLAY 0.680851 (5235 3960);
PAINT MONO (5235 3960);
FORCEPROP 0 LASTPIN (5225 4000) $PN 130
J 0
(5235 4010);
DISPLAY 0.680851 (5235 4010);
PAINT MONO (5235 4010);
FORCEPROP 0 LASTPIN (5225 4050) $PN 132
J 0
(5235 4060);
DISPLAY 0.680851 (5235 4060);
PAINT MONO (5235 4060);
FORCEPROP 0 LASTPIN (5225 4100) $PN 134
J 0
(5235 4110);
DISPLAY 0.680851 (5235 4110);
PAINT MONO (5235 4110);
FORCEPROP 0 LASTPIN (5225 4150) $PN 136
J 0
(5235 4160);
DISPLAY 0.680851 (5235 4160);
PAINT MONO (5235 4160);
FORCEPROP 0 LASTPIN (5225 4200) $PN 139
J 0
(5235 4210);
DISPLAY 0.680851 (5235 4210);
PAINT MONO (5235 4210);
FORCEPROP 0 LASTPIN (5225 4250) $PN 141
J 0
(5235 4260);
DISPLAY 0.680851 (5235 4260);
PAINT MONO (5235 4260);
FORCEPROP 0 LASTPIN (5225 4300) $PN 143
J 0
(5235 4310);
DISPLAY 0.680851 (5235 4310);
PAINT MONO (5235 4310);
FORCEPROP 0 LASTPIN (4025 1050) $PN 151
J 2
(4015 1060);
DISPLAY 0.680851 (4015 1060);
PAINT MONO (4015 1060);
FORCEPROP 0 LASTPIN (4025 1100) $PN 153
J 2
(4015 1110);
DISPLAY 0.680851 (4015 1110);
PAINT MONO (4015 1110);
FORCEPROP 0 LASTPIN (4025 1150) $PN 155
J 2
(4015 1160);
DISPLAY 0.680851 (4015 1160);
PAINT MONO (4015 1160);
FORCEPROP 0 LASTPIN (4025 1200) $PN 158
J 2
(4015 1210);
DISPLAY 0.680851 (4015 1210);
PAINT MONO (4015 1210);
FORCEPROP 0 LASTPIN (4025 1250) $PN 160
J 2
(4015 1260);
DISPLAY 0.680851 (4015 1260);
PAINT MONO (4015 1260);
FORCEPROP 0 LASTPIN (4025 1300) $PN 162
J 2
(4015 1310);
DISPLAY 0.680851 (4015 1310);
PAINT MONO (4015 1310);
FORCEPROP 0 LASTPIN (4025 1350) $PN 164
J 2
(4015 1360);
DISPLAY 0.680851 (4015 1360);
PAINT MONO (4015 1360);
FORCEPROP 0 LASTPIN (4025 1400) $PN 166
J 2
(4015 1410);
DISPLAY 0.680851 (4015 1410);
PAINT MONO (4015 1410);
FORCEPROP 0 LASTPIN (4025 1450) $PN 169
J 2
(4015 1460);
DISPLAY 0.680851 (4015 1460);
PAINT MONO (4015 1460);
FORCEPROP 0 LASTPIN (4025 1500) $PN 171
J 2
(4015 1510);
DISPLAY 0.680851 (4015 1510);
PAINT MONO (4015 1510);
FORCEPROP 0 LASTPIN (4025 1550) $PN 173
J 2
(4015 1560);
DISPLAY 0.680851 (4015 1560);
PAINT MONO (4015 1560);
FORCEPROP 0 LASTPIN (4025 1600) $PN 175
J 2
(4015 1610);
DISPLAY 0.680851 (4015 1610);
PAINT MONO (4015 1610);
FORCEPROP 0 LASTPIN (4025 1650) $PN 177
J 2
(4015 1660);
DISPLAY 0.680851 (4015 1660);
PAINT MONO (4015 1660);
FORCEPROP 0 LASTPIN (4025 1700) $PN 180
J 2
(4015 1710);
DISPLAY 0.680851 (4015 1710);
PAINT MONO (4015 1710);
FORCEPROP 0 LASTPIN (4025 1750) $PN 182
J 2
(4015 1760);
DISPLAY 0.680851 (4015 1760);
PAINT MONO (4015 1760);
FORCEPROP 0 LASTPIN (4025 1800) $PN 184
J 2
(4015 1810);
DISPLAY 0.680851 (4015 1810);
PAINT MONO (4015 1810);
FORCEPROP 0 LASTPIN (4025 1850) $PN 186
J 2
(4015 1860);
DISPLAY 0.680851 (4015 1860);
PAINT MONO (4015 1860);
FORCEPROP 0 LASTPIN (4025 1900) $PN 188
J 2
(4015 1910);
DISPLAY 0.680851 (4015 1910);
PAINT MONO (4015 1910);
FORCEPROP 0 LASTPIN (4025 1950) $PN 191
J 2
(4015 1960);
DISPLAY 0.680851 (4015 1960);
PAINT MONO (4015 1960);
FORCEPROP 0 LASTPIN (4025 2000) $PN 193
J 2
(4015 2010);
DISPLAY 0.680851 (4015 2010);
PAINT MONO (4015 2010);
FORCEPROP 0 LASTPIN (4025 2050) $PN 195
J 2
(4015 2060);
DISPLAY 0.680851 (4015 2060);
PAINT MONO (4015 2060);
FORCEPROP 0 LASTPIN (4025 2100) $PN 197
J 2
(4015 2110);
DISPLAY 0.680851 (4015 2110);
PAINT MONO (4015 2110);
FORCEPROP 0 LASTPIN (4025 2150) $PN 199
J 2
(4015 2160);
DISPLAY 0.680851 (4015 2160);
PAINT MONO (4015 2160);
FORCEPROP 0 LASTPIN (4025 2200) $PN 202
J 2
(4015 2210);
DISPLAY 0.680851 (4015 2210);
PAINT MONO (4015 2210);
FORCEPROP 0 LASTPIN (4025 2250) $PN 204
J 2
(4015 2260);
DISPLAY 0.680851 (4015 2260);
PAINT MONO (4015 2260);
FORCEPROP 0 LASTPIN (4025 2300) $PN 206
J 2
(4015 2310);
DISPLAY 0.680851 (4015 2310);
PAINT MONO (4015 2310);
FORCEPROP 0 LASTPIN (4025 2350) $PN 208
J 2
(4015 2360);
DISPLAY 0.680851 (4015 2360);
PAINT MONO (4015 2360);
FORCEPROP 0 LASTPIN (4025 2400) $PN 210
J 2
(4015 2410);
DISPLAY 0.680851 (4015 2410);
PAINT MONO (4015 2410);
FORCEPROP 0 LASTPIN (4025 2450) $PN 212
J 2
(4015 2460);
DISPLAY 0.680851 (4015 2460);
PAINT MONO (4015 2460);
FORCEPROP 0 LASTPIN (4025 2500) $PN 214
J 2
(4015 2510);
DISPLAY 0.680851 (4015 2510);
PAINT MONO (4015 2510);
FORCEPROP 0 LASTPIN (4025 2550) $PN 216
J 2
(4015 2560);
DISPLAY 0.680851 (4015 2560);
PAINT MONO (4015 2560);
FORCEPROP 0 LASTPIN (4025 2600) $PN 219
J 2
(4015 2610);
DISPLAY 0.680851 (4015 2610);
PAINT MONO (4015 2610);
FORCEPROP 0 LASTPIN (4025 2650) $PN 222
J 2
(4015 2660);
DISPLAY 0.680851 (4015 2660);
PAINT MONO (4015 2660);
FORCEPROP 0 LASTPIN (4025 2700) $PN 224
J 2
(4015 2710);
DISPLAY 0.680851 (4015 2710);
PAINT MONO (4015 2710);
FORCEPROP 0 LASTPIN (4025 2750) $PN 226
J 2
(4015 2760);
DISPLAY 0.680851 (4015 2760);
PAINT MONO (4015 2760);
FORCEPROP 0 LASTPIN (4025 2800) $PN 228
J 2
(4015 2810);
DISPLAY 0.680851 (4015 2810);
PAINT MONO (4015 2810);
FORCEPROP 0 LASTPIN (4025 2850) $PN 230
J 2
(4015 2860);
DISPLAY 0.680851 (4015 2860);
PAINT MONO (4015 2860);
FORCEPROP 0 LASTPIN (4025 2900) $PN 233
J 2
(4015 2910);
DISPLAY 0.680851 (4015 2910);
PAINT MONO (4015 2910);
FORCEPROP 0 LASTPIN (4025 2950) $PN 235
J 2
(4015 2960);
DISPLAY 0.680851 (4015 2960);
PAINT MONO (4015 2960);
FORCEPROP 0 LASTPIN (4025 3000) $PN 237
J 2
(4015 3010);
DISPLAY 0.680851 (4015 3010);
PAINT MONO (4015 3010);
FORCEPROP 0 LASTPIN (4025 3050) $PN 240
J 2
(4015 3060);
DISPLAY 0.680851 (4015 3060);
PAINT MONO (4015 3060);
FORCEPROP 0 LASTPIN (4025 3100) $PN 242
J 2
(4015 3110);
DISPLAY 0.680851 (4015 3110);
PAINT MONO (4015 3110);
FORCEPROP 0 LASTPIN (4025 3150) $PN 244
J 2
(4015 3160);
DISPLAY 0.680851 (4015 3160);
PAINT MONO (4015 3160);
FORCEPROP 0 LASTPIN (4025 3200) $PN 246
J 2
(4015 3210);
DISPLAY 0.680851 (4015 3210);
PAINT MONO (4015 3210);
FORCEPROP 0 LASTPIN (4025 3250) $PN 248
J 2
(4015 3260);
DISPLAY 0.680851 (4015 3260);
PAINT MONO (4015 3260);
FORCEPROP 0 LASTPIN (4025 3300) $PN 251
J 2
(4015 3310);
DISPLAY 0.680851 (4015 3310);
PAINT MONO (4015 3310);
FORCEPROP 0 LASTPIN (4025 3350) $PN 253
J 2
(4015 3360);
DISPLAY 0.680851 (4015 3360);
PAINT MONO (4015 3360);
FORCEPROP 0 LASTPIN (4025 3400) $PN 255
J 2
(4015 3410);
DISPLAY 0.680851 (4015 3410);
PAINT MONO (4015 3410);
FORCEPROP 0 LASTPIN (4025 3450) $PN 257
J 2
(4015 3460);
DISPLAY 0.680851 (4015 3460);
PAINT MONO (4015 3460);
FORCEPROP 0 LASTPIN (4025 3500) $PN 259
J 2
(4015 3510);
DISPLAY 0.680851 (4015 3510);
PAINT MONO (4015 3510);
FORCEPROP 0 LASTPIN (4025 3550) $PN 262
J 2
(4015 3560);
DISPLAY 0.680851 (4015 3560);
PAINT MONO (4015 3560);
FORCEPROP 0 LASTPIN (4025 3600) $PN 264
J 2
(4015 3610);
DISPLAY 0.680851 (4015 3610);
PAINT MONO (4015 3610);
FORCEPROP 0 LASTPIN (4025 3650) $PN 266
J 2
(4015 3660);
DISPLAY 0.680851 (4015 3660);
PAINT MONO (4015 3660);
FORCEPROP 0 LASTPIN (4025 3700) $PN 268
J 2
(4015 3710);
DISPLAY 0.680851 (4015 3710);
PAINT MONO (4015 3710);
FORCEPROP 0 LASTPIN (4025 3750) $PN 270
J 2
(4015 3760);
DISPLAY 0.680851 (4015 3760);
PAINT MONO (4015 3760);
FORCEPROP 0 LASTPIN (4025 3800) $PN 273
J 2
(4015 3810);
DISPLAY 0.680851 (4015 3810);
PAINT MONO (4015 3810);
FORCEPROP 0 LASTPIN (4025 3850) $PN 275
J 2
(4015 3860);
DISPLAY 0.680851 (4015 3860);
PAINT MONO (4015 3860);
FORCEPROP 0 LASTPIN (4025 3900) $PN 277
J 2
(4015 3910);
DISPLAY 0.680851 (4015 3910);
PAINT MONO (4015 3910);
FORCEPROP 0 LASTPIN (4025 3950) $PN 279
J 2
(4015 3960);
DISPLAY 0.680851 (4015 3960);
PAINT MONO (4015 3960);
FORCEPROP 0 LASTPIN (4025 4000) $PN 281
J 2
(4015 4010);
DISPLAY 0.680851 (4015 4010);
PAINT MONO (4015 4010);
FORCEPROP 0 LASTPIN (4025 4050) $PN 284
J 2
(4015 4060);
DISPLAY 0.680851 (4015 4060);
PAINT MONO (4015 4060);
FORCEPROP 0 LASTPIN (4025 4100) $PN 286
J 2
(4015 4110);
DISPLAY 0.680851 (4015 4110);
PAINT MONO (4015 4110);
FORCEPROP 0 LASTPIN (4025 4150) $PN 288
J 2
(4015 4160);
DISPLAY 0.680851 (4015 4160);
PAINT MONO (4015 4160);
FORCEPROP 2 LAST CDS_LIB pure_quanta
J 0
(4625 2675);
DISPLAY INVISIBLE (4625 2675);
FORCEPROP 1 LAST CDS_LMAN_SYM_OUTLINE -450,1775,450,-1775
J 0
(4625 2675);
DISPLAY 0.468085 (4625 2675);
PAINT GREEN (4625 2675);
DISPLAY INVISIBLE (4625 2675);
FORCEPROP 1 LAST NEEDS_NO_SIZE TRUE
J 0
(4625 2675);
DISPLAY 0.723404 (4625 2675);
PAINT GREEN (4625 2675);
DISPLAY INVISIBLE (4625 2675);
FORCEPROP 0 LAST $SEC 3
J 0
(4175 4900);
DISPLAY 0.680851 (4175 4900);
PAINT MONO (4175 4900);
DISPLAY INVISIBLE (4175 4900);
FORCEPROP 0 LAST CDS_SEC 3
J 0
(4175 4900);
DISPLAY 1.021277 (4175 4900);
DISPLAY INVISIBLE (4175 4900);
FORCEPROP 1 LAST PATH I203
J 0
(4625 2675);
DISPLAY 0.723404 (4625 2675);
PAINT GREEN (4625 2675);
DISPLAY INVISIBLE (4625 2675);
FORCEADD Q_RES..1
(-3275 1625);
FORCEPROP 1 LAST PART_NUMBER CS04992FB07
J 0
(-3175 1600);
DISPLAY 0.404255 (-3175 1600);
DISPLAY INVISIBLE (-3175 1600);
FORCEPROP 1 LAST VALUE 49.9
J 2
(-3050 1625);
DISPLAY 0.510638 (-3050 1625);
FORCEPROP 1 LAST MATERIAL CHIP
J 0
(-3150 1650);
DISPLAY 0.404255 (-3150 1650);
FORCEPROP 1 LAST TOLERANCE 1%
J 0
(-3025 1625);
DISPLAY 0.510638 (-3025 1625);
FORCEPROP 1 LAST $LOCATION R3875
J 0
(-3525 1625);
DISPLAY 0.638298 (-3525 1625);
FORCEPROP 1 LASTPIN (-3375 1625) $PN 1
J 0
(-3363 1637);
DISPLAY 0.787234 (-3363 1637);
PAINT MONO (-3363 1637);
FORCEPROP 1 LASTPIN (-3175 1625) $PN 2
J 0
(-3213 1637);
DISPLAY 0.787234 (-3213 1637);
PAINT MONO (-3213 1637);
FORCEPROP 1 LAST WATTAGE 1/16W
J 2
(-2975 1575);
DISPLAY 0.404255 (-2975 1575);
DISPLAY INVISIBLE (-2975 1575);
FORCEPROP 1 LAST PACK_TYPE 0402LF
J 0
(-2975 1625);
DISPLAY 0.510638 (-2975 1625);
DISPLAY INVISIBLE (-2975 1625);
FORCEPROP 2 LAST CDS_LIB pure_quanta
J 0
(-3275 1625);
DISPLAY INVISIBLE (-3275 1625);
FORCEPROP 0 LAST CDS_LOCATION R3875
J 0
(-3400 1675);
DISPLAY 1.021277 (-3400 1675);
DISPLAY INVISIBLE (-3400 1675);
FORCEPROP 0 LAST $SEC 1
J 0
(-3400 1675);
DISPLAY 0.680851 (-3400 1675);
PAINT MONO (-3400 1675);
DISPLAY INVISIBLE (-3400 1675);
FORCEPROP 0 LAST CDS_SEC 1
J 0
(-3400 1675);
DISPLAY 1.021277 (-3400 1675);
DISPLAY INVISIBLE (-3400 1675);
FORCEPROP 1 LAST PATH I204
J 0
(-3325 1775);
DISPLAY 0.978723 (-3325 1775);
PAINT WHITE (-3325 1775);
DISPLAY INVISIBLE (-3325 1775);
FORCEADD OFFPAGE..1
(-2125 1550);
FORCEPROP 2 LAST $XR7 89 
J 0
(-3007 1550);
DISPLAY 0.638298 (-3007 1550);
PAINT MONO (-3007 1550);
FORCEPROP 2 LAST $XR6 88 
J 0
(-2917 1550);
DISPLAY 0.638298 (-2917 1550);
PAINT MONO (-2917 1550);
FORCEPROP 2 LAST $XR5 87 
J 0
(-2827 1550);
DISPLAY 0.638298 (-2827 1550);
PAINT MONO (-2827 1550);
FORCEPROP 2 LAST $XR4 86 
J 0
(-2737 1550);
DISPLAY 0.638298 (-2737 1550);
PAINT MONO (-2737 1550);
FORCEPROP 2 LAST $XR3 85 
J 0
(-2647 1550);
DISPLAY 0.638298 (-2647 1550);
PAINT MONO (-2647 1550);
FORCEPROP 2 LAST $XR2 84 
J 0
(-2557 1550);
DISPLAY 0.638298 (-2557 1550);
PAINT MONO (-2557 1550);
FORCEPROP 2 LAST $XR1 83 
J 0
(-2467 1550);
DISPLAY 0.638298 (-2467 1550);
PAINT MONO (-2467 1550);
FORCEPROP 2 LAST $XR0 229 
J 0
(-2377 1550);
DISPLAY 0.638298 (-2377 1550);
PAINT MONO (-2377 1550);
FORCEPROP 2 LAST CDS_LIB standard
J 0
(-2125 1550);
PAINT MONO (-2125 1550);
DISPLAY INVISIBLE (-2125 1550);
FORCEPROP 1 LAST OFFPAGE TRUE
J 0
(-1800 1425);
DISPLAY 0.872340 (-1800 1425);
DISPLAY INVISIBLE (-1800 1425);
FORCEPROP 1 LAST COMMENT_BODY TRUE
J 0
(-2000 1450);
DISPLAY 0.872340 (-2000 1450);
PAINT GREEN (-2000 1450);
DISPLAY INVISIBLE (-2000 1450);
FORCEPROP 2 LAST PATH I205
J 2
(-3100 1600);
DISPLAY 1.021277 (-3100 1600);
DISPLAY INVISIBLE (-3100 1600);
FORCEADD TAP..1
(-650 3400);
FORCEPROP 3 LASTPIN (-700 3400) SIG_NAME M_A_CPU0_SA_DQ<13>
J 0
(-690 3410);
DISPLAY 0.659574 (-690 3410);
PAINT MONO (-690 3410);
DISPLAY INVISIBLE (-690 3410);
FORCEPROP 1 LASTPIN (-700 3400) BN 13
J 0
(-712 3408);
DISPLAY 0.680851 (-712 3408);
PAINT GREEN (-712 3408);
FORCEPROP 2 LAST CDS_LIB standard
J 0
(-650 3400);
PAINT MONO (-650 3400);
DISPLAY INVISIBLE (-650 3400);
FORCEPROP 1 LAST BODY_TYPE PLUMBING
J 0
(-650 3450);
DISPLAY 0.872340 (-650 3450);
PAINT GREEN (-650 3450);
DISPLAY INVISIBLE (-650 3450);
FORCEPROP 1 LAST HDL_TAP TRUE
J 0
(-325 3275);
DISPLAY 0.872340 (-325 3275);
DISPLAY INVISIBLE (-325 3275);
FORCEPROP 1 LAST PATH I21
J 0
(-652 3400);
DISPLAY 0.872340 (-652 3400);
PAINT GREEN (-652 3400);
DISPLAY INVISIBLE (-652 3400);
FORCEADD TAP..1
(-650 3500);
FORCEPROP 3 LASTPIN (-700 3500) SIG_NAME M_A_CPU0_SA_DQ<15>
J 0
(-690 3510);
DISPLAY 0.659574 (-690 3510);
PAINT MONO (-690 3510);
DISPLAY INVISIBLE (-690 3510);
FORCEPROP 1 LASTPIN (-700 3500) BN 15
J 0
(-712 3508);
DISPLAY 0.680851 (-712 3508);
PAINT GREEN (-712 3508);
FORCEPROP 2 LAST CDS_LIB standard
J 0
(-650 3500);
PAINT MONO (-650 3500);
DISPLAY INVISIBLE (-650 3500);
FORCEPROP 1 LAST BODY_TYPE PLUMBING
J 0
(-650 3550);
DISPLAY 0.872340 (-650 3550);
PAINT GREEN (-650 3550);
DISPLAY INVISIBLE (-650 3550);
FORCEPROP 1 LAST HDL_TAP TRUE
J 0
(-325 3375);
DISPLAY 0.872340 (-325 3375);
DISPLAY INVISIBLE (-325 3375);
FORCEPROP 1 LAST PATH I22
J 0
(-652 3500);
DISPLAY 0.872340 (-652 3500);
PAINT GREEN (-652 3500);
DISPLAY INVISIBLE (-652 3500);
FORCEADD TAP..1
(-650 3450);
FORCEPROP 3 LASTPIN (-700 3450) SIG_NAME M_A_CPU0_SA_DQ<14>
J 0
(-690 3460);
DISPLAY 0.659574 (-690 3460);
PAINT MONO (-690 3460);
DISPLAY INVISIBLE (-690 3460);
FORCEPROP 1 LASTPIN (-700 3450) BN 14
J 0
(-712 3458);
DISPLAY 0.680851 (-712 3458);
PAINT GREEN (-712 3458);
FORCEPROP 2 LAST CDS_LIB standard
J 0
(-650 3450);
PAINT MONO (-650 3450);
DISPLAY INVISIBLE (-650 3450);
FORCEPROP 1 LAST BODY_TYPE PLUMBING
J 0
(-650 3500);
DISPLAY 0.872340 (-650 3500);
PAINT GREEN (-650 3500);
DISPLAY INVISIBLE (-650 3500);
FORCEPROP 1 LAST HDL_TAP TRUE
J 0
(-325 3325);
DISPLAY 0.872340 (-325 3325);
DISPLAY INVISIBLE (-325 3325);
FORCEPROP 1 LAST PATH I23
J 0
(-652 3450);
DISPLAY 0.872340 (-652 3450);
PAINT GREEN (-652 3450);
DISPLAY INVISIBLE (-652 3450);
FORCEADD TAP..1
(-650 2800);
FORCEPROP 3 LASTPIN (-700 2800) SIG_NAME M_A_CPU0_SA_DQ<1>
J 0
(-690 2810);
DISPLAY 0.659574 (-690 2810);
PAINT MONO (-690 2810);
DISPLAY INVISIBLE (-690 2810);
FORCEPROP 1 LASTPIN (-700 2800) BN 1
J 0
(-712 2808);
DISPLAY 0.680851 (-712 2808);
PAINT GREEN (-712 2808);
FORCEPROP 2 LAST CDS_LIB standard
J 0
(-650 2800);
PAINT MONO (-650 2800);
DISPLAY INVISIBLE (-650 2800);
FORCEPROP 1 LAST BODY_TYPE PLUMBING
J 0
(-650 2850);
DISPLAY 0.872340 (-650 2850);
PAINT GREEN (-650 2850);
DISPLAY INVISIBLE (-650 2850);
FORCEPROP 1 LAST HDL_TAP TRUE
J 0
(-325 2675);
DISPLAY 0.872340 (-325 2675);
DISPLAY INVISIBLE (-325 2675);
FORCEPROP 1 LAST PATH I24
J 0
(-652 2800);
DISPLAY 0.872340 (-652 2800);
PAINT GREEN (-652 2800);
DISPLAY INVISIBLE (-652 2800);
FORCEADD TAP..1
(-650 2850);
FORCEPROP 3 LASTPIN (-700 2850) SIG_NAME M_A_CPU0_SA_DQ<2>
J 0
(-690 2860);
DISPLAY 0.659574 (-690 2860);
PAINT MONO (-690 2860);
DISPLAY INVISIBLE (-690 2860);
FORCEPROP 1 LASTPIN (-700 2850) BN 2
J 0
(-712 2858);
DISPLAY 0.680851 (-712 2858);
PAINT GREEN (-712 2858);
FORCEPROP 2 LAST CDS_LIB standard
J 0
(-650 2850);
PAINT MONO (-650 2850);
DISPLAY INVISIBLE (-650 2850);
FORCEPROP 1 LAST BODY_TYPE PLUMBING
J 0
(-650 2900);
DISPLAY 0.872340 (-650 2900);
PAINT GREEN (-650 2900);
DISPLAY INVISIBLE (-650 2900);
FORCEPROP 1 LAST HDL_TAP TRUE
J 0
(-325 2725);
DISPLAY 0.872340 (-325 2725);
DISPLAY INVISIBLE (-325 2725);
FORCEPROP 1 LAST PATH I25
J 0
(-652 2850);
DISPLAY 0.872340 (-652 2850);
PAINT GREEN (-652 2850);
DISPLAY INVISIBLE (-652 2850);
FORCEADD TAP..1
(-650 2750);
FORCEPROP 3 LASTPIN (-700 2750) SIG_NAME M_A_CPU0_SA_DQ<0>
J 0
(-690 2760);
DISPLAY 0.659574 (-690 2760);
PAINT MONO (-690 2760);
DISPLAY INVISIBLE (-690 2760);
FORCEPROP 1 LASTPIN (-700 2750) BN 0
J 0
(-712 2758);
DISPLAY 0.680851 (-712 2758);
PAINT GREEN (-712 2758);
FORCEPROP 2 LAST CDS_LIB standard
J 0
(-650 2750);
PAINT MONO (-650 2750);
DISPLAY INVISIBLE (-650 2750);
FORCEPROP 1 LAST BODY_TYPE PLUMBING
J 0
(-650 2800);
DISPLAY 0.872340 (-650 2800);
PAINT GREEN (-650 2800);
DISPLAY INVISIBLE (-650 2800);
FORCEPROP 1 LAST HDL_TAP TRUE
J 0
(-325 2625);
DISPLAY 0.872340 (-325 2625);
DISPLAY INVISIBLE (-325 2625);
FORCEPROP 1 LAST PATH I26
J 0
(-652 2750);
DISPLAY 0.872340 (-652 2750);
PAINT GREEN (-652 2750);
DISPLAY INVISIBLE (-652 2750);
FORCEADD TAP..1
(-650 2900);
FORCEPROP 3 LASTPIN (-700 2900) SIG_NAME M_A_CPU0_SA_DQ<3>
J 0
(-690 2910);
DISPLAY 0.659574 (-690 2910);
PAINT MONO (-690 2910);
DISPLAY INVISIBLE (-690 2910);
FORCEPROP 1 LASTPIN (-700 2900) BN 3
J 0
(-712 2908);
DISPLAY 0.680851 (-712 2908);
PAINT GREEN (-712 2908);
FORCEPROP 2 LAST CDS_LIB standard
J 0
(-650 2900);
PAINT MONO (-650 2900);
DISPLAY INVISIBLE (-650 2900);
FORCEPROP 1 LAST BODY_TYPE PLUMBING
J 0
(-650 2950);
DISPLAY 0.872340 (-650 2950);
PAINT GREEN (-650 2950);
DISPLAY INVISIBLE (-650 2950);
FORCEPROP 1 LAST HDL_TAP TRUE
J 0
(-325 2775);
DISPLAY 0.872340 (-325 2775);
DISPLAY INVISIBLE (-325 2775);
FORCEPROP 1 LAST PATH I27
J 0
(-652 2900);
DISPLAY 0.872340 (-652 2900);
PAINT GREEN (-652 2900);
DISPLAY INVISIBLE (-652 2900);
FORCEADD TAP..1
(-650 2950);
FORCEPROP 3 LASTPIN (-700 2950) SIG_NAME M_A_CPU0_SA_DQ<4>
J 0
(-690 2960);
DISPLAY 0.659574 (-690 2960);
PAINT MONO (-690 2960);
DISPLAY INVISIBLE (-690 2960);
FORCEPROP 1 LASTPIN (-700 2950) BN 4
J 0
(-712 2958);
DISPLAY 0.680851 (-712 2958);
PAINT GREEN (-712 2958);
FORCEPROP 2 LAST CDS_LIB standard
J 0
(-650 2950);
PAINT MONO (-650 2950);
DISPLAY INVISIBLE (-650 2950);
FORCEPROP 1 LAST BODY_TYPE PLUMBING
J 0
(-650 3000);
DISPLAY 0.872340 (-650 3000);
PAINT GREEN (-650 3000);
DISPLAY INVISIBLE (-650 3000);
FORCEPROP 1 LAST HDL_TAP TRUE
J 0
(-325 2825);
DISPLAY 0.872340 (-325 2825);
DISPLAY INVISIBLE (-325 2825);
FORCEPROP 1 LAST PATH I28
J 0
(-652 2950);
DISPLAY 0.872340 (-652 2950);
PAINT GREEN (-652 2950);
DISPLAY INVISIBLE (-652 2950);
FORCEADD TAP..1
(-650 3000);
FORCEPROP 3 LASTPIN (-700 3000) SIG_NAME M_A_CPU0_SA_DQ<5>
J 0
(-690 3010);
DISPLAY 0.659574 (-690 3010);
PAINT MONO (-690 3010);
DISPLAY INVISIBLE (-690 3010);
FORCEPROP 1 LASTPIN (-700 3000) BN 5
J 0
(-712 3008);
DISPLAY 0.680851 (-712 3008);
PAINT GREEN (-712 3008);
FORCEPROP 2 LAST CDS_LIB standard
J 0
(-650 3000);
PAINT MONO (-650 3000);
DISPLAY INVISIBLE (-650 3000);
FORCEPROP 1 LAST BODY_TYPE PLUMBING
J 0
(-650 3050);
DISPLAY 0.872340 (-650 3050);
PAINT GREEN (-650 3050);
DISPLAY INVISIBLE (-650 3050);
FORCEPROP 1 LAST HDL_TAP TRUE
J 0
(-325 2875);
DISPLAY 0.872340 (-325 2875);
DISPLAY INVISIBLE (-325 2875);
FORCEPROP 1 LAST PATH I29
J 0
(-652 3000);
DISPLAY 0.872340 (-652 3000);
PAINT GREEN (-652 3000);
DISPLAY INVISIBLE (-652 3000);
FORCEADD TAP..1
(-650 3150);
FORCEPROP 3 LASTPIN (-700 3150) SIG_NAME M_A_CPU0_SA_DQ<8>
J 0
(-690 3160);
DISPLAY 0.659574 (-690 3160);
PAINT MONO (-690 3160);
DISPLAY INVISIBLE (-690 3160);
FORCEPROP 1 LASTPIN (-700 3150) BN 8
J 0
(-712 3158);
DISPLAY 0.680851 (-712 3158);
PAINT GREEN (-712 3158);
FORCEPROP 2 LAST CDS_LIB standard
J 0
(-650 3150);
PAINT MONO (-650 3150);
DISPLAY INVISIBLE (-650 3150);
FORCEPROP 1 LAST BODY_TYPE PLUMBING
J 0
(-650 3200);
DISPLAY 0.872340 (-650 3200);
PAINT GREEN (-650 3200);
DISPLAY INVISIBLE (-650 3200);
FORCEPROP 1 LAST HDL_TAP TRUE
J 0
(-325 3025);
DISPLAY 0.872340 (-325 3025);
DISPLAY INVISIBLE (-325 3025);
FORCEPROP 1 LAST PATH I30
J 0
(-652 3150);
DISPLAY 0.872340 (-652 3150);
PAINT GREEN (-652 3150);
DISPLAY INVISIBLE (-652 3150);
FORCEADD TAP..1
(-650 3100);
FORCEPROP 3 LASTPIN (-700 3100) SIG_NAME M_A_CPU0_SA_DQ<7>
J 0
(-690 3110);
DISPLAY 0.659574 (-690 3110);
PAINT MONO (-690 3110);
DISPLAY INVISIBLE (-690 3110);
FORCEPROP 1 LASTPIN (-700 3100) BN 7
J 0
(-712 3108);
DISPLAY 0.680851 (-712 3108);
PAINT GREEN (-712 3108);
FORCEPROP 2 LAST CDS_LIB standard
J 0
(-650 3100);
PAINT MONO (-650 3100);
DISPLAY INVISIBLE (-650 3100);
FORCEPROP 1 LAST BODY_TYPE PLUMBING
J 0
(-650 3150);
DISPLAY 0.872340 (-650 3150);
PAINT GREEN (-650 3150);
DISPLAY INVISIBLE (-650 3150);
FORCEPROP 1 LAST HDL_TAP TRUE
J 0
(-325 2975);
DISPLAY 0.872340 (-325 2975);
DISPLAY INVISIBLE (-325 2975);
FORCEPROP 1 LAST PATH I31
J 0
(-652 3100);
DISPLAY 0.872340 (-652 3100);
PAINT GREEN (-652 3100);
DISPLAY INVISIBLE (-652 3100);
FORCEADD TAP..1
(-650 3050);
FORCEPROP 3 LASTPIN (-700 3050) SIG_NAME M_A_CPU0_SA_DQ<6>
J 0
(-690 3060);
DISPLAY 0.659574 (-690 3060);
PAINT MONO (-690 3060);
DISPLAY INVISIBLE (-690 3060);
FORCEPROP 1 LASTPIN (-700 3050) BN 6
J 0
(-712 3058);
DISPLAY 0.680851 (-712 3058);
PAINT GREEN (-712 3058);
FORCEPROP 2 LAST CDS_LIB standard
J 0
(-650 3050);
PAINT MONO (-650 3050);
DISPLAY INVISIBLE (-650 3050);
FORCEPROP 1 LAST BODY_TYPE PLUMBING
J 0
(-650 3100);
DISPLAY 0.872340 (-650 3100);
PAINT GREEN (-650 3100);
DISPLAY INVISIBLE (-650 3100);
FORCEPROP 1 LAST HDL_TAP TRUE
J 0
(-325 2925);
DISPLAY 0.872340 (-325 2925);
DISPLAY INVISIBLE (-325 2925);
FORCEPROP 1 LAST PATH I32
J 0
(-652 3050);
DISPLAY 0.872340 (-652 3050);
PAINT GREEN (-652 3050);
DISPLAY INVISIBLE (-652 3050);
FORCEADD TAP..1
(-650 3200);
FORCEPROP 3 LASTPIN (-700 3200) SIG_NAME M_A_CPU0_SA_DQ<9>
J 0
(-690 3210);
DISPLAY 0.659574 (-690 3210);
PAINT MONO (-690 3210);
DISPLAY INVISIBLE (-690 3210);
FORCEPROP 1 LASTPIN (-700 3200) BN 9
J 0
(-712 3208);
DISPLAY 0.680851 (-712 3208);
PAINT GREEN (-712 3208);
FORCEPROP 2 LAST CDS_LIB standard
J 0
(-650 3200);
PAINT MONO (-650 3200);
DISPLAY INVISIBLE (-650 3200);
FORCEPROP 1 LAST BODY_TYPE PLUMBING
J 0
(-650 3250);
DISPLAY 0.872340 (-650 3250);
PAINT GREEN (-650 3250);
DISPLAY INVISIBLE (-650 3250);
FORCEPROP 1 LAST HDL_TAP TRUE
J 0
(-325 3075);
DISPLAY 0.872340 (-325 3075);
DISPLAY INVISIBLE (-325 3075);
FORCEPROP 1 LAST PATH I33
J 0
(-652 3200);
DISPLAY 0.872340 (-652 3200);
PAINT GREEN (-652 3200);
DISPLAY INVISIBLE (-652 3200);
FORCEADD TAP..1
(-650 3350);
FORCEPROP 3 LASTPIN (-700 3350) SIG_NAME M_A_CPU0_SA_DQ<12>
J 0
(-690 3360);
DISPLAY 0.659574 (-690 3360);
PAINT MONO (-690 3360);
DISPLAY INVISIBLE (-690 3360);
FORCEPROP 1 LASTPIN (-700 3350) BN 12
J 0
(-712 3358);
DISPLAY 0.680851 (-712 3358);
PAINT GREEN (-712 3358);
FORCEPROP 2 LAST CDS_LIB standard
J 0
(-650 3350);
PAINT MONO (-650 3350);
DISPLAY INVISIBLE (-650 3350);
FORCEPROP 1 LAST BODY_TYPE PLUMBING
J 0
(-650 3400);
DISPLAY 0.872340 (-650 3400);
PAINT GREEN (-650 3400);
DISPLAY INVISIBLE (-650 3400);
FORCEPROP 1 LAST HDL_TAP TRUE
J 0
(-325 3225);
DISPLAY 0.872340 (-325 3225);
DISPLAY INVISIBLE (-325 3225);
FORCEPROP 1 LAST PATH I34
J 0
(-652 3350);
DISPLAY 0.872340 (-652 3350);
PAINT GREEN (-652 3350);
DISPLAY INVISIBLE (-652 3350);
FORCEADD TAP..1
(-650 3300);
FORCEPROP 3 LASTPIN (-700 3300) SIG_NAME M_A_CPU0_SA_DQ<11>
J 0
(-690 3310);
DISPLAY 0.659574 (-690 3310);
PAINT MONO (-690 3310);
DISPLAY INVISIBLE (-690 3310);
FORCEPROP 1 LASTPIN (-700 3300) BN 11
J 0
(-712 3308);
DISPLAY 0.680851 (-712 3308);
PAINT GREEN (-712 3308);
FORCEPROP 2 LAST CDS_LIB standard
J 0
(-650 3300);
PAINT MONO (-650 3300);
DISPLAY INVISIBLE (-650 3300);
FORCEPROP 1 LAST BODY_TYPE PLUMBING
J 0
(-650 3350);
DISPLAY 0.872340 (-650 3350);
PAINT GREEN (-650 3350);
DISPLAY INVISIBLE (-650 3350);
FORCEPROP 1 LAST HDL_TAP TRUE
J 0
(-325 3175);
DISPLAY 0.872340 (-325 3175);
DISPLAY INVISIBLE (-325 3175);
FORCEPROP 1 LAST PATH I35
J 0
(-652 3300);
DISPLAY 0.872340 (-652 3300);
PAINT GREEN (-652 3300);
DISPLAY INVISIBLE (-652 3300);
FORCEADD TAP..1
(-650 3250);
FORCEPROP 3 LASTPIN (-700 3250) SIG_NAME M_A_CPU0_SA_DQ<10>
J 0
(-690 3260);
DISPLAY 0.659574 (-690 3260);
PAINT MONO (-690 3260);
DISPLAY INVISIBLE (-690 3260);
FORCEPROP 1 LASTPIN (-700 3250) BN 10
J 0
(-712 3258);
DISPLAY 0.680851 (-712 3258);
PAINT GREEN (-712 3258);
FORCEPROP 2 LAST CDS_LIB standard
J 0
(-650 3250);
PAINT MONO (-650 3250);
DISPLAY INVISIBLE (-650 3250);
FORCEPROP 1 LAST BODY_TYPE PLUMBING
J 0
(-650 3300);
DISPLAY 0.872340 (-650 3300);
PAINT GREEN (-650 3300);
DISPLAY INVISIBLE (-650 3300);
FORCEPROP 1 LAST HDL_TAP TRUE
J 0
(-325 3125);
DISPLAY 0.872340 (-325 3125);
DISPLAY INVISIBLE (-325 3125);
FORCEPROP 1 LAST PATH I36
J 0
(-652 3250);
DISPLAY 0.872340 (-652 3250);
PAINT GREEN (-652 3250);
DISPLAY INVISIBLE (-652 3250);
FORCEADD TAP..1
(-650 1150);
FORCEPROP 3 LASTPIN (-700 1150) SIG_NAME M_A_CPU0_SB_DQ<1>
J 0
(-690 1160);
DISPLAY 0.659574 (-690 1160);
PAINT MONO (-690 1160);
DISPLAY INVISIBLE (-690 1160);
FORCEPROP 1 LASTPIN (-700 1150) BN 1
J 0
(-712 1158);
DISPLAY 0.680851 (-712 1158);
PAINT GREEN (-712 1158);
FORCEPROP 2 LAST CDS_LIB standard
J 0
(-650 1150);
PAINT MONO (-650 1150);
DISPLAY INVISIBLE (-650 1150);
FORCEPROP 1 LAST BODY_TYPE PLUMBING
J 0
(-650 1200);
DISPLAY 0.872340 (-650 1200);
PAINT GREEN (-650 1200);
DISPLAY INVISIBLE (-650 1200);
FORCEPROP 1 LAST HDL_TAP TRUE
J 0
(-325 1025);
DISPLAY 0.872340 (-325 1025);
DISPLAY INVISIBLE (-325 1025);
FORCEPROP 1 LAST PATH I37
J 0
(-652 1150);
DISPLAY 0.872340 (-652 1150);
PAINT GREEN (-652 1150);
DISPLAY INVISIBLE (-652 1150);
FORCEADD TAP..1
(-650 1250);
FORCEPROP 3 LASTPIN (-700 1250) SIG_NAME M_A_CPU0_SB_DQ<3>
J 0
(-690 1260);
DISPLAY 0.659574 (-690 1260);
PAINT MONO (-690 1260);
DISPLAY INVISIBLE (-690 1260);
FORCEPROP 1 LASTPIN (-700 1250) BN 3
J 0
(-712 1258);
DISPLAY 0.680851 (-712 1258);
PAINT GREEN (-712 1258);
FORCEPROP 2 LAST CDS_LIB standard
J 0
(-650 1250);
PAINT MONO (-650 1250);
DISPLAY INVISIBLE (-650 1250);
FORCEPROP 1 LAST BODY_TYPE PLUMBING
J 0
(-650 1300);
DISPLAY 0.872340 (-650 1300);
PAINT GREEN (-650 1300);
DISPLAY INVISIBLE (-650 1300);
FORCEPROP 1 LAST HDL_TAP TRUE
J 0
(-325 1125);
DISPLAY 0.872340 (-325 1125);
DISPLAY INVISIBLE (-325 1125);
FORCEPROP 1 LAST PATH I38
J 0
(-652 1250);
DISPLAY 0.872340 (-652 1250);
PAINT GREEN (-652 1250);
DISPLAY INVISIBLE (-652 1250);
FORCEADD TAP..1
(-650 1200);
FORCEPROP 3 LASTPIN (-700 1200) SIG_NAME M_A_CPU0_SB_DQ<2>
J 0
(-690 1210);
DISPLAY 0.659574 (-690 1210);
PAINT MONO (-690 1210);
DISPLAY INVISIBLE (-690 1210);
FORCEPROP 1 LASTPIN (-700 1200) BN 2
J 0
(-712 1208);
DISPLAY 0.680851 (-712 1208);
PAINT GREEN (-712 1208);
FORCEPROP 2 LAST CDS_LIB standard
J 0
(-650 1200);
PAINT MONO (-650 1200);
DISPLAY INVISIBLE (-650 1200);
FORCEPROP 1 LAST BODY_TYPE PLUMBING
J 0
(-650 1250);
DISPLAY 0.872340 (-650 1250);
PAINT GREEN (-650 1250);
DISPLAY INVISIBLE (-650 1250);
FORCEPROP 1 LAST HDL_TAP TRUE
J 0
(-325 1075);
DISPLAY 0.872340 (-325 1075);
DISPLAY INVISIBLE (-325 1075);
FORCEPROP 1 LAST PATH I39
J 0
(-652 1200);
DISPLAY 0.872340 (-652 1200);
PAINT GREEN (-652 1200);
DISPLAY INVISIBLE (-652 1200);
FORCEADD TAP..1
(-650 3850);
FORCEPROP 3 LASTPIN (-700 3850) SIG_NAME M_A_CPU0_SA_DQ<22>
J 0
(-690 3860);
DISPLAY 0.659574 (-690 3860);
PAINT MONO (-690 3860);
DISPLAY INVISIBLE (-690 3860);
FORCEPROP 1 LASTPIN (-700 3850) BN 22
J 0
(-712 3858);
DISPLAY 0.680851 (-712 3858);
PAINT GREEN (-712 3858);
FORCEPROP 2 LAST CDS_LIB standard
J 0
(-650 3850);
DISPLAY INVISIBLE (-650 3850);
FORCEPROP 1 LAST BODY_TYPE PLUMBING
J 0
(-650 3900);
DISPLAY 0.872340 (-650 3900);
PAINT GREEN (-650 3900);
DISPLAY INVISIBLE (-650 3900);
FORCEPROP 1 LAST HDL_TAP TRUE
J 0
(-325 3725);
DISPLAY 0.872340 (-325 3725);
DISPLAY INVISIBLE (-325 3725);
FORCEPROP 1 LAST PATH I4
J 0
(-652 3850);
DISPLAY 0.872340 (-652 3850);
PAINT GREEN (-652 3850);
DISPLAY INVISIBLE (-652 3850);
FORCEADD TAP..1
(-650 1400);
FORCEPROP 3 LASTPIN (-700 1400) SIG_NAME M_A_CPU0_SB_DQ<6>
J 0
(-690 1410);
DISPLAY 0.659574 (-690 1410);
PAINT MONO (-690 1410);
DISPLAY INVISIBLE (-690 1410);
FORCEPROP 1 LASTPIN (-700 1400) BN 6
J 0
(-712 1408);
DISPLAY 0.680851 (-712 1408);
PAINT GREEN (-712 1408);
FORCEPROP 2 LAST CDS_LIB standard
J 0
(-650 1400);
PAINT MONO (-650 1400);
DISPLAY INVISIBLE (-650 1400);
FORCEPROP 1 LAST BODY_TYPE PLUMBING
J 0
(-650 1450);
DISPLAY 0.872340 (-650 1450);
PAINT GREEN (-650 1450);
DISPLAY INVISIBLE (-650 1450);
FORCEPROP 1 LAST HDL_TAP TRUE
J 0
(-325 1275);
DISPLAY 0.872340 (-325 1275);
DISPLAY INVISIBLE (-325 1275);
FORCEPROP 1 LAST PATH I40
J 0
(-652 1400);
DISPLAY 0.872340 (-652 1400);
PAINT GREEN (-652 1400);
DISPLAY INVISIBLE (-652 1400);
FORCEADD TAP..1
(-650 1350);
FORCEPROP 3 LASTPIN (-700 1350) SIG_NAME M_A_CPU0_SB_DQ<5>
J 0
(-690 1360);
DISPLAY 0.659574 (-690 1360);
PAINT MONO (-690 1360);
DISPLAY INVISIBLE (-690 1360);
FORCEPROP 1 LASTPIN (-700 1350) BN 5
J 0
(-712 1358);
DISPLAY 0.680851 (-712 1358);
PAINT GREEN (-712 1358);
FORCEPROP 2 LAST CDS_LIB standard
J 0
(-650 1350);
PAINT MONO (-650 1350);
DISPLAY INVISIBLE (-650 1350);
FORCEPROP 1 LAST BODY_TYPE PLUMBING
J 0
(-650 1400);
DISPLAY 0.872340 (-650 1400);
PAINT GREEN (-650 1400);
DISPLAY INVISIBLE (-650 1400);
FORCEPROP 1 LAST HDL_TAP TRUE
J 0
(-325 1225);
DISPLAY 0.872340 (-325 1225);
DISPLAY INVISIBLE (-325 1225);
FORCEPROP 1 LAST PATH I41
J 0
(-652 1350);
DISPLAY 0.872340 (-652 1350);
PAINT GREEN (-652 1350);
DISPLAY INVISIBLE (-652 1350);
FORCEADD TAP..1
(-650 1300);
FORCEPROP 3 LASTPIN (-700 1300) SIG_NAME M_A_CPU0_SB_DQ<4>
J 0
(-690 1310);
DISPLAY 0.659574 (-690 1310);
PAINT MONO (-690 1310);
DISPLAY INVISIBLE (-690 1310);
FORCEPROP 1 LASTPIN (-700 1300) BN 4
J 0
(-712 1308);
DISPLAY 0.680851 (-712 1308);
PAINT GREEN (-712 1308);
FORCEPROP 2 LAST CDS_LIB standard
J 0
(-650 1300);
PAINT MONO (-650 1300);
DISPLAY INVISIBLE (-650 1300);
FORCEPROP 1 LAST BODY_TYPE PLUMBING
J 0
(-650 1350);
DISPLAY 0.872340 (-650 1350);
PAINT GREEN (-650 1350);
DISPLAY INVISIBLE (-650 1350);
FORCEPROP 1 LAST HDL_TAP TRUE
J 0
(-325 1175);
DISPLAY 0.872340 (-325 1175);
DISPLAY INVISIBLE (-325 1175);
FORCEPROP 1 LAST PATH I42
J 0
(-652 1300);
DISPLAY 0.872340 (-652 1300);
PAINT GREEN (-652 1300);
DISPLAY INVISIBLE (-652 1300);
FORCEADD TAP..1
(-650 1450);
FORCEPROP 3 LASTPIN (-700 1450) SIG_NAME M_A_CPU0_SB_DQ<7>
J 0
(-690 1460);
DISPLAY 0.659574 (-690 1460);
PAINT MONO (-690 1460);
DISPLAY INVISIBLE (-690 1460);
FORCEPROP 1 LASTPIN (-700 1450) BN 7
J 0
(-712 1458);
DISPLAY 0.680851 (-712 1458);
PAINT GREEN (-712 1458);
FORCEPROP 2 LAST CDS_LIB standard
J 0
(-650 1450);
PAINT MONO (-650 1450);
DISPLAY INVISIBLE (-650 1450);
FORCEPROP 1 LAST BODY_TYPE PLUMBING
J 0
(-650 1500);
DISPLAY 0.872340 (-650 1500);
PAINT GREEN (-650 1500);
DISPLAY INVISIBLE (-650 1500);
FORCEPROP 1 LAST HDL_TAP TRUE
J 0
(-325 1325);
DISPLAY 0.872340 (-325 1325);
DISPLAY INVISIBLE (-325 1325);
FORCEPROP 1 LAST PATH I43
J 0
(-652 1450);
DISPLAY 0.872340 (-652 1450);
PAINT GREEN (-652 1450);
DISPLAY INVISIBLE (-652 1450);
FORCEADD TAP..1
(-650 1500);
FORCEPROP 3 LASTPIN (-700 1500) SIG_NAME M_A_CPU0_SB_DQ<8>
J 0
(-690 1510);
DISPLAY 0.659574 (-690 1510);
PAINT MONO (-690 1510);
DISPLAY INVISIBLE (-690 1510);
FORCEPROP 1 LASTPIN (-700 1500) BN 8
J 0
(-712 1508);
DISPLAY 0.680851 (-712 1508);
PAINT GREEN (-712 1508);
FORCEPROP 2 LAST CDS_LIB standard
J 0
(-650 1500);
PAINT MONO (-650 1500);
DISPLAY INVISIBLE (-650 1500);
FORCEPROP 1 LAST BODY_TYPE PLUMBING
J 0
(-650 1550);
DISPLAY 0.872340 (-650 1550);
PAINT GREEN (-650 1550);
DISPLAY INVISIBLE (-650 1550);
FORCEPROP 1 LAST HDL_TAP TRUE
J 0
(-325 1375);
DISPLAY 0.872340 (-325 1375);
DISPLAY INVISIBLE (-325 1375);
FORCEPROP 1 LAST PATH I44
J 0
(-652 1500);
DISPLAY 0.872340 (-652 1500);
PAINT GREEN (-652 1500);
DISPLAY INVISIBLE (-652 1500);
FORCEADD TAP..1
(-650 1550);
FORCEPROP 3 LASTPIN (-700 1550) SIG_NAME M_A_CPU0_SB_DQ<9>
J 0
(-690 1560);
DISPLAY 0.659574 (-690 1560);
PAINT MONO (-690 1560);
DISPLAY INVISIBLE (-690 1560);
FORCEPROP 1 LASTPIN (-700 1550) BN 9
J 0
(-712 1558);
DISPLAY 0.680851 (-712 1558);
PAINT GREEN (-712 1558);
FORCEPROP 2 LAST CDS_LIB standard
J 0
(-650 1550);
PAINT MONO (-650 1550);
DISPLAY INVISIBLE (-650 1550);
FORCEPROP 1 LAST BODY_TYPE PLUMBING
J 0
(-650 1600);
DISPLAY 0.872340 (-650 1600);
PAINT GREEN (-650 1600);
DISPLAY INVISIBLE (-650 1600);
FORCEPROP 1 LAST HDL_TAP TRUE
J 0
(-325 1425);
DISPLAY 0.872340 (-325 1425);
DISPLAY INVISIBLE (-325 1425);
FORCEPROP 1 LAST PATH I45
J 0
(-652 1550);
DISPLAY 0.872340 (-652 1550);
PAINT GREEN (-652 1550);
DISPLAY INVISIBLE (-652 1550);
FORCEADD TAP..1
(-650 1600);
FORCEPROP 3 LASTPIN (-700 1600) SIG_NAME M_A_CPU0_SB_DQ<10>
J 0
(-690 1610);
DISPLAY 0.659574 (-690 1610);
PAINT MONO (-690 1610);
DISPLAY INVISIBLE (-690 1610);
FORCEPROP 1 LASTPIN (-700 1600) BN 10
J 0
(-712 1608);
DISPLAY 0.680851 (-712 1608);
PAINT GREEN (-712 1608);
FORCEPROP 2 LAST CDS_LIB standard
J 0
(-650 1600);
PAINT MONO (-650 1600);
DISPLAY INVISIBLE (-650 1600);
FORCEPROP 1 LAST BODY_TYPE PLUMBING
J 0
(-650 1650);
DISPLAY 0.872340 (-650 1650);
PAINT GREEN (-650 1650);
DISPLAY INVISIBLE (-650 1650);
FORCEPROP 1 LAST HDL_TAP TRUE
J 0
(-325 1475);
DISPLAY 0.872340 (-325 1475);
DISPLAY INVISIBLE (-325 1475);
FORCEPROP 1 LAST PATH I46
J 0
(-652 1600);
DISPLAY 0.872340 (-652 1600);
PAINT GREEN (-652 1600);
DISPLAY INVISIBLE (-652 1600);
FORCEADD TAP..1
(-650 1650);
FORCEPROP 3 LASTPIN (-700 1650) SIG_NAME M_A_CPU0_SB_DQ<11>
J 0
(-690 1660);
DISPLAY 0.659574 (-690 1660);
PAINT MONO (-690 1660);
DISPLAY INVISIBLE (-690 1660);
FORCEPROP 1 LASTPIN (-700 1650) BN 11
J 0
(-712 1658);
DISPLAY 0.680851 (-712 1658);
PAINT GREEN (-712 1658);
FORCEPROP 2 LAST CDS_LIB standard
J 0
(-650 1650);
PAINT MONO (-650 1650);
DISPLAY INVISIBLE (-650 1650);
FORCEPROP 1 LAST BODY_TYPE PLUMBING
J 0
(-650 1700);
DISPLAY 0.872340 (-650 1700);
PAINT GREEN (-650 1700);
DISPLAY INVISIBLE (-650 1700);
FORCEPROP 1 LAST HDL_TAP TRUE
J 0
(-325 1525);
DISPLAY 0.872340 (-325 1525);
DISPLAY INVISIBLE (-325 1525);
FORCEPROP 1 LAST PATH I47
J 0
(-652 1650);
DISPLAY 0.872340 (-652 1650);
PAINT GREEN (-652 1650);
DISPLAY INVISIBLE (-652 1650);
FORCEADD TAP..1
(-650 1700);
FORCEPROP 3 LASTPIN (-700 1700) SIG_NAME M_A_CPU0_SB_DQ<12>
J 0
(-690 1710);
DISPLAY 0.659574 (-690 1710);
PAINT MONO (-690 1710);
DISPLAY INVISIBLE (-690 1710);
FORCEPROP 1 LASTPIN (-700 1700) BN 12
J 0
(-712 1708);
DISPLAY 0.680851 (-712 1708);
PAINT GREEN (-712 1708);
FORCEPROP 2 LAST CDS_LIB standard
J 0
(-650 1700);
PAINT MONO (-650 1700);
DISPLAY INVISIBLE (-650 1700);
FORCEPROP 1 LAST BODY_TYPE PLUMBING
J 0
(-650 1750);
DISPLAY 0.872340 (-650 1750);
PAINT GREEN (-650 1750);
DISPLAY INVISIBLE (-650 1750);
FORCEPROP 1 LAST HDL_TAP TRUE
J 0
(-325 1575);
DISPLAY 0.872340 (-325 1575);
DISPLAY INVISIBLE (-325 1575);
FORCEPROP 1 LAST PATH I48
J 0
(-652 1700);
DISPLAY 0.872340 (-652 1700);
PAINT GREEN (-652 1700);
DISPLAY INVISIBLE (-652 1700);
FORCEADD TAP..1
(-650 1800);
FORCEPROP 3 LASTPIN (-700 1800) SIG_NAME M_A_CPU0_SB_DQ<14>
J 0
(-690 1810);
DISPLAY 0.659574 (-690 1810);
PAINT MONO (-690 1810);
DISPLAY INVISIBLE (-690 1810);
FORCEPROP 1 LASTPIN (-700 1800) BN 14
J 0
(-712 1808);
DISPLAY 0.680851 (-712 1808);
PAINT GREEN (-712 1808);
FORCEPROP 2 LAST CDS_LIB standard
J 0
(-650 1800);
PAINT MONO (-650 1800);
DISPLAY INVISIBLE (-650 1800);
FORCEPROP 1 LAST BODY_TYPE PLUMBING
J 0
(-650 1850);
DISPLAY 0.872340 (-650 1850);
PAINT GREEN (-650 1850);
DISPLAY INVISIBLE (-650 1850);
FORCEPROP 1 LAST HDL_TAP TRUE
J 0
(-325 1675);
DISPLAY 0.872340 (-325 1675);
DISPLAY INVISIBLE (-325 1675);
FORCEPROP 1 LAST PATH I49
J 0
(-652 1800);
DISPLAY 0.872340 (-652 1800);
PAINT GREEN (-652 1800);
DISPLAY INVISIBLE (-652 1800);
FORCEADD TAP..1
(-650 3900);
FORCEPROP 3 LASTPIN (-700 3900) SIG_NAME M_A_CPU0_SA_DQ<23>
J 0
(-690 3910);
DISPLAY 0.659574 (-690 3910);
PAINT MONO (-690 3910);
DISPLAY INVISIBLE (-690 3910);
FORCEPROP 1 LASTPIN (-700 3900) BN 23
J 0
(-712 3908);
DISPLAY 0.680851 (-712 3908);
PAINT GREEN (-712 3908);
FORCEPROP 2 LAST CDS_LIB standard
J 0
(-650 3900);
DISPLAY INVISIBLE (-650 3900);
FORCEPROP 1 LAST BODY_TYPE PLUMBING
J 0
(-650 3950);
DISPLAY 0.872340 (-650 3950);
PAINT GREEN (-650 3950);
DISPLAY INVISIBLE (-650 3950);
FORCEPROP 1 LAST HDL_TAP TRUE
J 0
(-325 3775);
DISPLAY 0.872340 (-325 3775);
DISPLAY INVISIBLE (-325 3775);
FORCEPROP 1 LAST PATH I5
J 0
(-652 3900);
DISPLAY 0.872340 (-652 3900);
PAINT GREEN (-652 3900);
DISPLAY INVISIBLE (-652 3900);
FORCEADD TAP..1
(-650 1750);
FORCEPROP 3 LASTPIN (-700 1750) SIG_NAME M_A_CPU0_SB_DQ<13>
J 0
(-690 1760);
DISPLAY 0.659574 (-690 1760);
PAINT MONO (-690 1760);
DISPLAY INVISIBLE (-690 1760);
FORCEPROP 1 LASTPIN (-700 1750) BN 13
J 0
(-712 1758);
DISPLAY 0.680851 (-712 1758);
PAINT GREEN (-712 1758);
FORCEPROP 2 LAST CDS_LIB standard
J 0
(-650 1750);
PAINT MONO (-650 1750);
DISPLAY INVISIBLE (-650 1750);
FORCEPROP 1 LAST BODY_TYPE PLUMBING
J 0
(-650 1800);
DISPLAY 0.872340 (-650 1800);
PAINT GREEN (-650 1800);
DISPLAY INVISIBLE (-650 1800);
FORCEPROP 1 LAST HDL_TAP TRUE
J 0
(-325 1625);
DISPLAY 0.872340 (-325 1625);
DISPLAY INVISIBLE (-325 1625);
FORCEPROP 1 LAST PATH I50
J 0
(-652 1750);
DISPLAY 0.872340 (-652 1750);
PAINT GREEN (-652 1750);
DISPLAY INVISIBLE (-652 1750);
FORCEADD TAP..1
(-650 1850);
FORCEPROP 3 LASTPIN (-700 1850) SIG_NAME M_A_CPU0_SB_DQ<15>
J 0
(-690 1860);
DISPLAY 0.659574 (-690 1860);
PAINT MONO (-690 1860);
DISPLAY INVISIBLE (-690 1860);
FORCEPROP 1 LASTPIN (-700 1850) BN 15
J 0
(-712 1858);
DISPLAY 0.680851 (-712 1858);
PAINT GREEN (-712 1858);
FORCEPROP 2 LAST CDS_LIB standard
J 0
(-650 1850);
PAINT MONO (-650 1850);
DISPLAY INVISIBLE (-650 1850);
FORCEPROP 1 LAST BODY_TYPE PLUMBING
J 0
(-650 1900);
DISPLAY 0.872340 (-650 1900);
PAINT GREEN (-650 1900);
DISPLAY INVISIBLE (-650 1900);
FORCEPROP 1 LAST HDL_TAP TRUE
J 0
(-325 1725);
DISPLAY 0.872340 (-325 1725);
DISPLAY INVISIBLE (-325 1725);
FORCEPROP 1 LAST PATH I51
J 0
(-652 1850);
DISPLAY 0.872340 (-652 1850);
PAINT GREEN (-652 1850);
DISPLAY INVISIBLE (-652 1850);
FORCEADD TAP..1
(-650 1900);
FORCEPROP 3 LASTPIN (-700 1900) SIG_NAME M_A_CPU0_SB_DQ<16>
J 0
(-690 1910);
DISPLAY 0.659574 (-690 1910);
PAINT MONO (-690 1910);
DISPLAY INVISIBLE (-690 1910);
FORCEPROP 1 LASTPIN (-700 1900) BN 16
J 0
(-712 1908);
DISPLAY 0.680851 (-712 1908);
PAINT GREEN (-712 1908);
FORCEPROP 2 LAST CDS_LIB standard
J 0
(-650 1900);
PAINT MONO (-650 1900);
DISPLAY INVISIBLE (-650 1900);
FORCEPROP 1 LAST BODY_TYPE PLUMBING
J 0
(-650 1950);
DISPLAY 0.872340 (-650 1950);
PAINT GREEN (-650 1950);
DISPLAY INVISIBLE (-650 1950);
FORCEPROP 1 LAST HDL_TAP TRUE
J 0
(-325 1775);
DISPLAY 0.872340 (-325 1775);
DISPLAY INVISIBLE (-325 1775);
FORCEPROP 1 LAST PATH I52
J 0
(-652 1900);
DISPLAY 0.872340 (-652 1900);
PAINT GREEN (-652 1900);
DISPLAY INVISIBLE (-652 1900);
FORCEADD TAP..1
(-650 1950);
FORCEPROP 3 LASTPIN (-700 1950) SIG_NAME M_A_CPU0_SB_DQ<17>
J 0
(-690 1960);
DISPLAY 0.659574 (-690 1960);
PAINT MONO (-690 1960);
DISPLAY INVISIBLE (-690 1960);
FORCEPROP 1 LASTPIN (-700 1950) BN 17
J 0
(-712 1958);
DISPLAY 0.680851 (-712 1958);
PAINT GREEN (-712 1958);
FORCEPROP 2 LAST CDS_LIB standard
J 0
(-650 1950);
PAINT MONO (-650 1950);
DISPLAY INVISIBLE (-650 1950);
FORCEPROP 1 LAST BODY_TYPE PLUMBING
J 0
(-650 2000);
DISPLAY 0.872340 (-650 2000);
PAINT GREEN (-650 2000);
DISPLAY INVISIBLE (-650 2000);
FORCEPROP 1 LAST HDL_TAP TRUE
J 0
(-325 1825);
DISPLAY 0.872340 (-325 1825);
DISPLAY INVISIBLE (-325 1825);
FORCEPROP 1 LAST PATH I53
J 0
(-652 1950);
DISPLAY 0.872340 (-652 1950);
PAINT GREEN (-652 1950);
DISPLAY INVISIBLE (-652 1950);
FORCEADD TAP..1
(-650 2000);
FORCEPROP 3 LASTPIN (-700 2000) SIG_NAME M_A_CPU0_SB_DQ<18>
J 0
(-690 2010);
DISPLAY 0.659574 (-690 2010);
PAINT MONO (-690 2010);
DISPLAY INVISIBLE (-690 2010);
FORCEPROP 1 LASTPIN (-700 2000) BN 18
J 0
(-712 2008);
DISPLAY 0.680851 (-712 2008);
PAINT GREEN (-712 2008);
FORCEPROP 2 LAST CDS_LIB standard
J 0
(-650 2000);
PAINT MONO (-650 2000);
DISPLAY INVISIBLE (-650 2000);
FORCEPROP 1 LAST BODY_TYPE PLUMBING
J 0
(-650 2050);
DISPLAY 0.872340 (-650 2050);
PAINT GREEN (-650 2050);
DISPLAY INVISIBLE (-650 2050);
FORCEPROP 1 LAST HDL_TAP TRUE
J 0
(-325 1875);
DISPLAY 0.872340 (-325 1875);
DISPLAY INVISIBLE (-325 1875);
FORCEPROP 1 LAST PATH I54
J 0
(-652 2000);
DISPLAY 0.872340 (-652 2000);
PAINT GREEN (-652 2000);
DISPLAY INVISIBLE (-652 2000);
FORCEADD TAP..1
(-650 2050);
FORCEPROP 3 LASTPIN (-700 2050) SIG_NAME M_A_CPU0_SB_DQ<19>
J 0
(-690 2060);
DISPLAY 0.659574 (-690 2060);
PAINT MONO (-690 2060);
DISPLAY INVISIBLE (-690 2060);
FORCEPROP 1 LASTPIN (-700 2050) BN 19
J 0
(-712 2058);
DISPLAY 0.680851 (-712 2058);
PAINT GREEN (-712 2058);
FORCEPROP 2 LAST CDS_LIB standard
J 0
(-650 2050);
PAINT MONO (-650 2050);
DISPLAY INVISIBLE (-650 2050);
FORCEPROP 1 LAST BODY_TYPE PLUMBING
J 0
(-650 2100);
DISPLAY 0.872340 (-650 2100);
PAINT GREEN (-650 2100);
DISPLAY INVISIBLE (-650 2100);
FORCEPROP 1 LAST HDL_TAP TRUE
J 0
(-325 1925);
DISPLAY 0.872340 (-325 1925);
DISPLAY INVISIBLE (-325 1925);
FORCEPROP 1 LAST PATH I55
J 0
(-652 2050);
DISPLAY 0.872340 (-652 2050);
PAINT GREEN (-652 2050);
DISPLAY INVISIBLE (-652 2050);
FORCEADD TAP..1
(-650 2150);
FORCEPROP 3 LASTPIN (-700 2150) SIG_NAME M_A_CPU0_SB_DQ<21>
J 0
(-690 2160);
DISPLAY 0.659574 (-690 2160);
PAINT MONO (-690 2160);
DISPLAY INVISIBLE (-690 2160);
FORCEPROP 1 LASTPIN (-700 2150) BN 21
J 0
(-712 2158);
DISPLAY 0.680851 (-712 2158);
PAINT GREEN (-712 2158);
FORCEPROP 2 LAST CDS_LIB standard
J 0
(-650 2150);
PAINT MONO (-650 2150);
DISPLAY INVISIBLE (-650 2150);
FORCEPROP 1 LAST BODY_TYPE PLUMBING
J 0
(-650 2200);
DISPLAY 0.872340 (-650 2200);
PAINT GREEN (-650 2200);
DISPLAY INVISIBLE (-650 2200);
FORCEPROP 1 LAST HDL_TAP TRUE
J 0
(-325 2025);
DISPLAY 0.872340 (-325 2025);
DISPLAY INVISIBLE (-325 2025);
FORCEPROP 1 LAST PATH I56
J 0
(-652 2150);
DISPLAY 0.872340 (-652 2150);
PAINT GREEN (-652 2150);
DISPLAY INVISIBLE (-652 2150);
FORCEADD TAP..1
(-650 2100);
FORCEPROP 3 LASTPIN (-700 2100) SIG_NAME M_A_CPU0_SB_DQ<20>
J 0
(-690 2110);
DISPLAY 0.659574 (-690 2110);
PAINT MONO (-690 2110);
DISPLAY INVISIBLE (-690 2110);
FORCEPROP 1 LASTPIN (-700 2100) BN 20
J 0
(-712 2108);
DISPLAY 0.680851 (-712 2108);
PAINT GREEN (-712 2108);
FORCEPROP 2 LAST CDS_LIB standard
J 0
(-650 2100);
PAINT MONO (-650 2100);
DISPLAY INVISIBLE (-650 2100);
FORCEPROP 1 LAST BODY_TYPE PLUMBING
J 0
(-650 2150);
DISPLAY 0.872340 (-650 2150);
PAINT GREEN (-650 2150);
DISPLAY INVISIBLE (-650 2150);
FORCEPROP 1 LAST HDL_TAP TRUE
J 0
(-325 1975);
DISPLAY 0.872340 (-325 1975);
DISPLAY INVISIBLE (-325 1975);
FORCEPROP 1 LAST PATH I57
J 0
(-652 2100);
DISPLAY 0.872340 (-652 2100);
PAINT GREEN (-652 2100);
DISPLAY INVISIBLE (-652 2100);
FORCEADD TAP..1
(-650 2250);
FORCEPROP 3 LASTPIN (-700 2250) SIG_NAME M_A_CPU0_SB_DQ<23>
J 0
(-690 2260);
DISPLAY 0.659574 (-690 2260);
PAINT MONO (-690 2260);
DISPLAY INVISIBLE (-690 2260);
FORCEPROP 1 LASTPIN (-700 2250) BN 23
J 0
(-712 2258);
DISPLAY 0.680851 (-712 2258);
PAINT GREEN (-712 2258);
FORCEPROP 2 LAST CDS_LIB standard
J 0
(-650 2250);
DISPLAY INVISIBLE (-650 2250);
FORCEPROP 1 LAST BODY_TYPE PLUMBING
J 0
(-650 2300);
DISPLAY 0.872340 (-650 2300);
PAINT GREEN (-650 2300);
DISPLAY INVISIBLE (-650 2300);
FORCEPROP 1 LAST HDL_TAP TRUE
J 0
(-325 2125);
DISPLAY 0.872340 (-325 2125);
DISPLAY INVISIBLE (-325 2125);
FORCEPROP 1 LAST PATH I58
J 0
(-652 2250);
DISPLAY 0.872340 (-652 2250);
PAINT GREEN (-652 2250);
DISPLAY INVISIBLE (-652 2250);
FORCEADD TAP..1
(-650 2300);
FORCEPROP 3 LASTPIN (-700 2300) SIG_NAME M_A_CPU0_SB_DQ<24>
J 0
(-690 2310);
DISPLAY 0.659574 (-690 2310);
PAINT MONO (-690 2310);
DISPLAY INVISIBLE (-690 2310);
FORCEPROP 1 LASTPIN (-700 2300) BN 24
J 0
(-712 2308);
DISPLAY 0.680851 (-712 2308);
PAINT GREEN (-712 2308);
FORCEPROP 2 LAST CDS_LIB standard
J 0
(-650 2300);
DISPLAY INVISIBLE (-650 2300);
FORCEPROP 1 LAST BODY_TYPE PLUMBING
J 0
(-650 2350);
DISPLAY 0.872340 (-650 2350);
PAINT GREEN (-650 2350);
DISPLAY INVISIBLE (-650 2350);
FORCEPROP 1 LAST HDL_TAP TRUE
J 0
(-325 2175);
DISPLAY 0.872340 (-325 2175);
DISPLAY INVISIBLE (-325 2175);
FORCEPROP 1 LAST PATH I59
J 0
(-652 2300);
DISPLAY 0.872340 (-652 2300);
PAINT GREEN (-652 2300);
DISPLAY INVISIBLE (-652 2300);
FORCEADD TAP..1
(-650 3950);
FORCEPROP 3 LASTPIN (-700 3950) SIG_NAME M_A_CPU0_SA_DQ<24>
J 0
(-690 3960);
DISPLAY 0.659574 (-690 3960);
PAINT MONO (-690 3960);
DISPLAY INVISIBLE (-690 3960);
FORCEPROP 1 LASTPIN (-700 3950) BN 24
J 0
(-712 3958);
DISPLAY 0.680851 (-712 3958);
PAINT GREEN (-712 3958);
FORCEPROP 2 LAST CDS_LIB standard
J 0
(-650 3950);
DISPLAY INVISIBLE (-650 3950);
FORCEPROP 1 LAST BODY_TYPE PLUMBING
J 0
(-650 4000);
DISPLAY 0.872340 (-650 4000);
PAINT GREEN (-650 4000);
DISPLAY INVISIBLE (-650 4000);
FORCEPROP 1 LAST HDL_TAP TRUE
J 0
(-325 3825);
DISPLAY 0.872340 (-325 3825);
DISPLAY INVISIBLE (-325 3825);
FORCEPROP 1 LAST PATH I6
J 0
(-652 3950);
DISPLAY 0.872340 (-652 3950);
PAINT GREEN (-652 3950);
DISPLAY INVISIBLE (-652 3950);
FORCEADD TAP..1
(-650 2200);
FORCEPROP 3 LASTPIN (-700 2200) SIG_NAME M_A_CPU0_SB_DQ<22>
J 0
(-690 2210);
DISPLAY 0.659574 (-690 2210);
PAINT MONO (-690 2210);
DISPLAY INVISIBLE (-690 2210);
FORCEPROP 1 LASTPIN (-700 2200) BN 22
J 0
(-712 2208);
DISPLAY 0.680851 (-712 2208);
PAINT GREEN (-712 2208);
FORCEPROP 2 LAST CDS_LIB standard
J 0
(-650 2200);
DISPLAY INVISIBLE (-650 2200);
FORCEPROP 1 LAST BODY_TYPE PLUMBING
J 0
(-650 2250);
DISPLAY 0.872340 (-650 2250);
PAINT GREEN (-650 2250);
DISPLAY INVISIBLE (-650 2250);
FORCEPROP 1 LAST HDL_TAP TRUE
J 0
(-325 2075);
DISPLAY 0.872340 (-325 2075);
DISPLAY INVISIBLE (-325 2075);
FORCEPROP 1 LAST PATH I60
J 0
(-652 2200);
DISPLAY 0.872340 (-652 2200);
PAINT GREEN (-652 2200);
DISPLAY INVISIBLE (-652 2200);
FORCEADD TAP..1
(-650 2350);
FORCEPROP 3 LASTPIN (-700 2350) SIG_NAME M_A_CPU0_SB_DQ<25>
J 0
(-690 2360);
DISPLAY 0.659574 (-690 2360);
PAINT MONO (-690 2360);
DISPLAY INVISIBLE (-690 2360);
FORCEPROP 1 LASTPIN (-700 2350) BN 25
J 0
(-712 2358);
DISPLAY 0.680851 (-712 2358);
PAINT GREEN (-712 2358);
FORCEPROP 2 LAST CDS_LIB standard
J 0
(-650 2350);
DISPLAY INVISIBLE (-650 2350);
FORCEPROP 1 LAST BODY_TYPE PLUMBING
J 0
(-650 2400);
DISPLAY 0.872340 (-650 2400);
PAINT GREEN (-650 2400);
DISPLAY INVISIBLE (-650 2400);
FORCEPROP 1 LAST HDL_TAP TRUE
J 0
(-325 2225);
DISPLAY 0.872340 (-325 2225);
DISPLAY INVISIBLE (-325 2225);
FORCEPROP 1 LAST PATH I61
J 0
(-652 2350);
DISPLAY 0.872340 (-652 2350);
PAINT GREEN (-652 2350);
DISPLAY INVISIBLE (-652 2350);
FORCEADD TAP..1
(-650 2400);
FORCEPROP 3 LASTPIN (-700 2400) SIG_NAME M_A_CPU0_SB_DQ<26>
J 0
(-690 2410);
DISPLAY 0.659574 (-690 2410);
PAINT MONO (-690 2410);
DISPLAY INVISIBLE (-690 2410);
FORCEPROP 1 LASTPIN (-700 2400) BN 26
J 0
(-712 2408);
DISPLAY 0.680851 (-712 2408);
PAINT GREEN (-712 2408);
FORCEPROP 2 LAST CDS_LIB standard
J 0
(-650 2400);
DISPLAY INVISIBLE (-650 2400);
FORCEPROP 1 LAST BODY_TYPE PLUMBING
J 0
(-650 2450);
DISPLAY 0.872340 (-650 2450);
PAINT GREEN (-650 2450);
DISPLAY INVISIBLE (-650 2450);
FORCEPROP 1 LAST HDL_TAP TRUE
J 0
(-325 2275);
DISPLAY 0.872340 (-325 2275);
DISPLAY INVISIBLE (-325 2275);
FORCEPROP 1 LAST PATH I62
J 0
(-652 2400);
DISPLAY 0.872340 (-652 2400);
PAINT GREEN (-652 2400);
DISPLAY INVISIBLE (-652 2400);
FORCEADD TAP..1
(-650 2450);
FORCEPROP 3 LASTPIN (-700 2450) SIG_NAME M_A_CPU0_SB_DQ<27>
J 0
(-690 2460);
DISPLAY 0.659574 (-690 2460);
PAINT MONO (-690 2460);
DISPLAY INVISIBLE (-690 2460);
FORCEPROP 1 LASTPIN (-700 2450) BN 27
J 0
(-712 2458);
DISPLAY 0.680851 (-712 2458);
PAINT GREEN (-712 2458);
FORCEPROP 2 LAST CDS_LIB standard
J 0
(-650 2450);
DISPLAY INVISIBLE (-650 2450);
FORCEPROP 1 LAST BODY_TYPE PLUMBING
J 0
(-650 2500);
DISPLAY 0.872340 (-650 2500);
PAINT GREEN (-650 2500);
DISPLAY INVISIBLE (-650 2500);
FORCEPROP 1 LAST HDL_TAP TRUE
J 0
(-325 2325);
DISPLAY 0.872340 (-325 2325);
DISPLAY INVISIBLE (-325 2325);
FORCEPROP 1 LAST PATH I63
J 0
(-652 2450);
DISPLAY 0.872340 (-652 2450);
PAINT GREEN (-652 2450);
DISPLAY INVISIBLE (-652 2450);
FORCEADD TAP..1
(-650 2550);
FORCEPROP 3 LASTPIN (-700 2550) SIG_NAME M_A_CPU0_SB_DQ<29>
J 0
(-690 2560);
DISPLAY 0.659574 (-690 2560);
PAINT MONO (-690 2560);
DISPLAY INVISIBLE (-690 2560);
FORCEPROP 1 LASTPIN (-700 2550) BN 29
J 0
(-712 2558);
DISPLAY 0.680851 (-712 2558);
PAINT GREEN (-712 2558);
FORCEPROP 2 LAST CDS_LIB standard
J 0
(-650 2550);
DISPLAY INVISIBLE (-650 2550);
FORCEPROP 1 LAST BODY_TYPE PLUMBING
J 0
(-650 2600);
DISPLAY 0.872340 (-650 2600);
PAINT GREEN (-650 2600);
DISPLAY INVISIBLE (-650 2600);
FORCEPROP 1 LAST HDL_TAP TRUE
J 0
(-325 2425);
DISPLAY 0.872340 (-325 2425);
DISPLAY INVISIBLE (-325 2425);
FORCEPROP 1 LAST PATH I64
J 0
(-652 2550);
DISPLAY 0.872340 (-652 2550);
PAINT GREEN (-652 2550);
DISPLAY INVISIBLE (-652 2550);
FORCEADD TAP..1
(-650 2500);
FORCEPROP 3 LASTPIN (-700 2500) SIG_NAME M_A_CPU0_SB_DQ<28>
J 0
(-690 2510);
DISPLAY 0.659574 (-690 2510);
PAINT MONO (-690 2510);
DISPLAY INVISIBLE (-690 2510);
FORCEPROP 1 LASTPIN (-700 2500) BN 28
J 0
(-712 2508);
DISPLAY 0.680851 (-712 2508);
PAINT GREEN (-712 2508);
FORCEPROP 2 LAST CDS_LIB standard
J 0
(-650 2500);
DISPLAY INVISIBLE (-650 2500);
FORCEPROP 1 LAST BODY_TYPE PLUMBING
J 0
(-650 2550);
DISPLAY 0.872340 (-650 2550);
PAINT GREEN (-650 2550);
DISPLAY INVISIBLE (-650 2550);
FORCEPROP 1 LAST HDL_TAP TRUE
J 0
(-325 2375);
DISPLAY 0.872340 (-325 2375);
DISPLAY INVISIBLE (-325 2375);
FORCEPROP 1 LAST PATH I65
J 0
(-652 2500);
DISPLAY 0.872340 (-652 2500);
PAINT GREEN (-652 2500);
DISPLAY INVISIBLE (-652 2500);
FORCEADD TAP..1
(-650 2600);
FORCEPROP 3 LASTPIN (-700 2600) SIG_NAME M_A_CPU0_SB_DQ<30>
J 0
(-690 2610);
DISPLAY 0.659574 (-690 2610);
PAINT MONO (-690 2610);
DISPLAY INVISIBLE (-690 2610);
FORCEPROP 1 LASTPIN (-700 2600) BN 30
J 0
(-712 2608);
DISPLAY 0.680851 (-712 2608);
PAINT GREEN (-712 2608);
FORCEPROP 2 LAST CDS_LIB standard
J 0
(-650 2600);
DISPLAY INVISIBLE (-650 2600);
FORCEPROP 1 LAST BODY_TYPE PLUMBING
J 0
(-650 2650);
DISPLAY 0.872340 (-650 2650);
PAINT GREEN (-650 2650);
DISPLAY INVISIBLE (-650 2650);
FORCEPROP 1 LAST HDL_TAP TRUE
J 0
(-325 2475);
DISPLAY 0.872340 (-325 2475);
DISPLAY INVISIBLE (-325 2475);
FORCEPROP 1 LAST PATH I66
J 0
(-652 2600);
DISPLAY 0.872340 (-652 2600);
PAINT GREEN (-652 2600);
DISPLAY INVISIBLE (-652 2600);
FORCEADD TAP..1
(-650 2650);
FORCEPROP 3 LASTPIN (-700 2650) SIG_NAME M_A_CPU0_SB_DQ<31>
J 0
(-690 2660);
DISPLAY 0.659574 (-690 2660);
PAINT MONO (-690 2660);
DISPLAY INVISIBLE (-690 2660);
FORCEPROP 1 LASTPIN (-700 2650) BN 31
J 0
(-712 2658);
DISPLAY 0.680851 (-712 2658);
PAINT GREEN (-712 2658);
FORCEPROP 2 LAST CDS_LIB standard
J 0
(-650 2650);
DISPLAY INVISIBLE (-650 2650);
FORCEPROP 1 LAST BODY_TYPE PLUMBING
J 0
(-650 2700);
DISPLAY 0.872340 (-650 2700);
PAINT GREEN (-650 2700);
DISPLAY INVISIBLE (-650 2700);
FORCEPROP 1 LAST HDL_TAP TRUE
J 0
(-325 2525);
DISPLAY 0.872340 (-325 2525);
DISPLAY INVISIBLE (-325 2525);
FORCEPROP 1 LAST PATH I67
J 0
(-652 2650);
DISPLAY 0.872340 (-652 2650);
PAINT GREEN (-652 2650);
DISPLAY INVISIBLE (-652 2650);
FORCEADD OFFPAGE..3
(175 2675);
FORCEPROP 2 LAST $XR1 83 
J 0
(479 2675);
DISPLAY 0.638298 (479 2675);
PAINT MONO (479 2675);
FORCEPROP 2 LAST $XR0 20 
J 0
(389 2675);
DISPLAY 0.638298 (389 2675);
PAINT MONO (389 2675);
FORCEPROP 2 LAST CDS_LIB standard
J 2
(175 2675);
DISPLAY INVISIBLE (175 2675);
FORCEPROP 1 LAST OFFPAGE TRUE
J 0
(500 2550);
DISPLAY 0.872340 (500 2550);
DISPLAY INVISIBLE (500 2550);
FORCEPROP 1 LAST COMMENT_BODY TRUE
J 0
(125 2575);
DISPLAY 0.872340 (125 2575);
PAINT GREEN (125 2575);
DISPLAY INVISIBLE (125 2575);
FORCEPROP 2 LAST PATH I68
J 0
(375 2750);
DISPLAY 1.021277 (375 2750);
DISPLAY INVISIBLE (375 2750);
FORCEADD TAP..1
(-650 1100);
FORCEPROP 3 LASTPIN (-700 1100) SIG_NAME M_A_CPU0_SB_DQ<0>
J 0
(-690 1110);
DISPLAY 0.659574 (-690 1110);
PAINT MONO (-690 1110);
DISPLAY INVISIBLE (-690 1110);
FORCEPROP 1 LASTPIN (-700 1100) BN 0
J 0
(-712 1108);
DISPLAY 0.680851 (-712 1108);
PAINT GREEN (-712 1108);
FORCEPROP 2 LAST CDS_LIB standard
J 0
(-650 1100);
PAINT MONO (-650 1100);
DISPLAY INVISIBLE (-650 1100);
FORCEPROP 1 LAST BODY_TYPE PLUMBING
J 0
(-650 1150);
DISPLAY 0.872340 (-650 1150);
PAINT GREEN (-650 1150);
DISPLAY INVISIBLE (-650 1150);
FORCEPROP 1 LAST HDL_TAP TRUE
J 0
(-325 975);
DISPLAY 0.872340 (-325 975);
DISPLAY INVISIBLE (-325 975);
FORCEPROP 1 LAST PATH I69
J 0
(-652 1100);
DISPLAY 0.872340 (-652 1100);
PAINT GREEN (-652 1100);
DISPLAY INVISIBLE (-652 1100);
FORCEADD TAP..1
(-650 4000);
FORCEPROP 3 LASTPIN (-700 4000) SIG_NAME M_A_CPU0_SA_DQ<25>
J 0
(-690 4010);
DISPLAY 0.659574 (-690 4010);
PAINT MONO (-690 4010);
DISPLAY INVISIBLE (-690 4010);
FORCEPROP 1 LASTPIN (-700 4000) BN 25
J 0
(-712 4008);
DISPLAY 0.680851 (-712 4008);
PAINT GREEN (-712 4008);
FORCEPROP 2 LAST CDS_LIB standard
J 0
(-650 4000);
DISPLAY INVISIBLE (-650 4000);
FORCEPROP 1 LAST BODY_TYPE PLUMBING
J 0
(-650 4050);
DISPLAY 0.872340 (-650 4050);
PAINT GREEN (-650 4050);
DISPLAY INVISIBLE (-650 4050);
FORCEPROP 1 LAST HDL_TAP TRUE
J 0
(-325 3875);
DISPLAY 0.872340 (-325 3875);
DISPLAY INVISIBLE (-325 3875);
FORCEPROP 1 LAST PATH I7
J 0
(-652 4000);
DISPLAY 0.872340 (-652 4000);
PAINT GREEN (-652 4000);
DISPLAY INVISIBLE (-652 4000);
FORCEADD TAP..1
(2200 4000);
FORCEPROP 3 LASTPIN (2150 4000) SIG_NAME M_A_CPU0_SA_DQS_DP<6>
J 0
(2160 4010);
DISPLAY 0.659574 (2160 4010);
PAINT MONO (2160 4010);
DISPLAY INVISIBLE (2160 4010);
FORCEPROP 1 LASTPIN (2150 4000) BN 6
J 0
(2138 4008);
DISPLAY 0.680851 (2138 4008);
PAINT GREEN (2138 4008);
FORCEPROP 2 LAST CDS_LIB standard
J 0
(2200 4000);
DISPLAY INVISIBLE (2200 4000);
FORCEPROP 1 LAST BODY_TYPE PLUMBING
J 0
(2200 4050);
DISPLAY 0.872340 (2200 4050);
PAINT GREEN (2200 4050);
DISPLAY INVISIBLE (2200 4050);
FORCEPROP 1 LAST HDL_TAP TRUE
J 0
(2525 3875);
DISPLAY 0.872340 (2525 3875);
DISPLAY INVISIBLE (2525 3875);
FORCEPROP 1 LAST PATH I72
J 0
(2198 4000);
DISPLAY 0.872340 (2198 4000);
PAINT GREEN (2198 4000);
DISPLAY INVISIBLE (2198 4000);
FORCEADD TAP..1
(2200 4100);
FORCEPROP 3 LASTPIN (2150 4100) SIG_NAME M_A_CPU0_SA_DQS_DP<7>
J 0
(2160 4110);
DISPLAY 0.659574 (2160 4110);
PAINT MONO (2160 4110);
DISPLAY INVISIBLE (2160 4110);
FORCEPROP 1 LASTPIN (2150 4100) BN 7
J 0
(2138 4108);
DISPLAY 0.680851 (2138 4108);
PAINT GREEN (2138 4108);
FORCEPROP 2 LAST CDS_LIB standard
J 0
(2200 4100);
DISPLAY INVISIBLE (2200 4100);
FORCEPROP 1 LAST BODY_TYPE PLUMBING
J 0
(2200 4150);
DISPLAY 0.872340 (2200 4150);
PAINT GREEN (2200 4150);
DISPLAY INVISIBLE (2200 4150);
FORCEPROP 1 LAST HDL_TAP TRUE
J 0
(2525 3975);
DISPLAY 0.872340 (2525 3975);
DISPLAY INVISIBLE (2525 3975);
FORCEPROP 1 LAST PATH I74
J 0
(2198 4100);
DISPLAY 0.872340 (2198 4100);
PAINT GREEN (2198 4100);
DISPLAY INVISIBLE (2198 4100);
FORCEADD TAP..1
(2200 4200);
FORCEPROP 3 LASTPIN (2150 4200) SIG_NAME M_A_CPU0_SA_DQS_DP<8>
J 0
(2160 4210);
DISPLAY 0.659574 (2160 4210);
PAINT MONO (2160 4210);
DISPLAY INVISIBLE (2160 4210);
FORCEPROP 1 LASTPIN (2150 4200) BN 8
J 0
(2138 4208);
DISPLAY 0.680851 (2138 4208);
PAINT GREEN (2138 4208);
FORCEPROP 2 LAST CDS_LIB standard
J 0
(2200 4200);
DISPLAY INVISIBLE (2200 4200);
FORCEPROP 1 LAST BODY_TYPE PLUMBING
J 0
(2200 4250);
DISPLAY 0.872340 (2200 4250);
PAINT GREEN (2200 4250);
DISPLAY INVISIBLE (2200 4250);
FORCEPROP 1 LAST HDL_TAP TRUE
J 0
(2525 4075);
DISPLAY 0.872340 (2525 4075);
DISPLAY INVISIBLE (2525 4075);
FORCEPROP 1 LAST PATH I75
J 0
(2198 4200);
DISPLAY 0.872340 (2198 4200);
PAINT GREEN (2198 4200);
DISPLAY INVISIBLE (2198 4200);
FORCEADD TAP..1
(2200 4300);
FORCEPROP 3 LASTPIN (2150 4300) SIG_NAME M_A_CPU0_SA_DQS_DP<9>
J 0
(2160 4310);
DISPLAY 0.659574 (2160 4310);
PAINT MONO (2160 4310);
DISPLAY INVISIBLE (2160 4310);
FORCEPROP 1 LASTPIN (2150 4300) BN 9
J 0
(2138 4308);
DISPLAY 0.680851 (2138 4308);
PAINT GREEN (2138 4308);
FORCEPROP 2 LAST CDS_LIB standard
J 0
(2200 4300);
DISPLAY INVISIBLE (2200 4300);
FORCEPROP 1 LAST BODY_TYPE PLUMBING
J 0
(2200 4350);
DISPLAY 0.872340 (2200 4350);
PAINT GREEN (2200 4350);
DISPLAY INVISIBLE (2200 4350);
FORCEPROP 1 LAST HDL_TAP TRUE
J 0
(2525 4175);
DISPLAY 0.872340 (2525 4175);
DISPLAY INVISIBLE (2525 4175);
FORCEPROP 1 LAST PATH I78
J 0
(2198 4300);
DISPLAY 0.872340 (2198 4300);
PAINT GREEN (2198 4300);
DISPLAY INVISIBLE (2198 4300);
FORCEADD TAP..1
(-650 4100);
FORCEPROP 3 LASTPIN (-700 4100) SIG_NAME M_A_CPU0_SA_DQ<27>
J 0
(-690 4110);
DISPLAY 0.659574 (-690 4110);
PAINT MONO (-690 4110);
DISPLAY INVISIBLE (-690 4110);
FORCEPROP 1 LASTPIN (-700 4100) BN 27
J 0
(-712 4108);
DISPLAY 0.680851 (-712 4108);
PAINT GREEN (-712 4108);
FORCEPROP 2 LAST CDS_LIB standard
J 0
(-650 4100);
DISPLAY INVISIBLE (-650 4100);
FORCEPROP 1 LAST BODY_TYPE PLUMBING
J 0
(-650 4150);
DISPLAY 0.872340 (-650 4150);
PAINT GREEN (-650 4150);
DISPLAY INVISIBLE (-650 4150);
FORCEPROP 1 LAST HDL_TAP TRUE
J 0
(-325 3975);
DISPLAY 0.872340 (-325 3975);
DISPLAY INVISIBLE (-325 3975);
FORCEPROP 1 LAST PATH I8
J 0
(-652 4100);
DISPLAY 0.872340 (-652 4100);
PAINT GREEN (-652 4100);
DISPLAY INVISIBLE (-652 4100);
FORCEADD TAP..1
(2200 3700);
FORCEPROP 3 LASTPIN (2150 3700) SIG_NAME M_A_CPU0_SA_DQS_DP<3>
J 0
(2160 3710);
DISPLAY 0.659574 (2160 3710);
PAINT MONO (2160 3710);
DISPLAY INVISIBLE (2160 3710);
FORCEPROP 1 LASTPIN (2150 3700) BN 3
J 0
(2138 3708);
DISPLAY 0.680851 (2138 3708);
PAINT GREEN (2138 3708);
FORCEPROP 2 LAST CDS_LIB standard
J 0
(2200 3700);
PAINT MONO (2200 3700);
DISPLAY INVISIBLE (2200 3700);
FORCEPROP 1 LAST BODY_TYPE PLUMBING
J 0
(2200 3750);
DISPLAY 0.872340 (2200 3750);
PAINT GREEN (2200 3750);
DISPLAY INVISIBLE (2200 3750);
FORCEPROP 1 LAST HDL_TAP TRUE
J 0
(2525 3575);
DISPLAY 0.872340 (2525 3575);
DISPLAY INVISIBLE (2525 3575);
FORCEPROP 1 LAST PATH I80
J 0
(2198 3700);
DISPLAY 0.872340 (2198 3700);
PAINT GREEN (2198 3700);
DISPLAY INVISIBLE (2198 3700);
FORCEADD TAP..1
(2200 3800);
FORCEPROP 3 LASTPIN (2150 3800) SIG_NAME M_A_CPU0_SA_DQS_DP<4>
J 0
(2160 3810);
DISPLAY 0.659574 (2160 3810);
PAINT MONO (2160 3810);
DISPLAY INVISIBLE (2160 3810);
FORCEPROP 1 LASTPIN (2150 3800) BN 4
J 0
(2138 3808);
DISPLAY 0.680851 (2138 3808);
PAINT GREEN (2138 3808);
FORCEPROP 2 LAST CDS_LIB standard
J 0
(2200 3800);
PAINT MONO (2200 3800);
DISPLAY INVISIBLE (2200 3800);
FORCEPROP 1 LAST BODY_TYPE PLUMBING
J 0
(2200 3850);
DISPLAY 0.872340 (2200 3850);
PAINT GREEN (2200 3850);
DISPLAY INVISIBLE (2200 3850);
FORCEPROP 1 LAST HDL_TAP TRUE
J 0
(2525 3675);
DISPLAY 0.872340 (2525 3675);
DISPLAY INVISIBLE (2525 3675);
FORCEPROP 1 LAST PATH I82
J 0
(2198 3800);
DISPLAY 0.872340 (2198 3800);
PAINT GREEN (2198 3800);
DISPLAY INVISIBLE (2198 3800);
FORCEADD TAP..1
(2200 3900);
FORCEPROP 3 LASTPIN (2150 3900) SIG_NAME M_A_CPU0_SA_DQS_DP<5>
J 0
(2160 3910);
DISPLAY 0.659574 (2160 3910);
PAINT MONO (2160 3910);
DISPLAY INVISIBLE (2160 3910);
FORCEPROP 1 LASTPIN (2150 3900) BN 5
J 0
(2138 3908);
DISPLAY 0.680851 (2138 3908);
PAINT GREEN (2138 3908);
FORCEPROP 2 LAST CDS_LIB standard
J 0
(2200 3900);
DISPLAY INVISIBLE (2200 3900);
FORCEPROP 1 LAST BODY_TYPE PLUMBING
J 0
(2200 3950);
DISPLAY 0.872340 (2200 3950);
PAINT GREEN (2200 3950);
DISPLAY INVISIBLE (2200 3950);
FORCEPROP 1 LAST HDL_TAP TRUE
J 0
(2525 3775);
DISPLAY 0.872340 (2525 3775);
DISPLAY INVISIBLE (2525 3775);
FORCEPROP 1 LAST PATH I84
J 0
(2198 3900);
DISPLAY 0.872340 (2198 3900);
PAINT GREEN (2198 3900);
DISPLAY INVISIBLE (2198 3900);
FORCEADD TAP..1
(2200 3400);
FORCEPROP 3 LASTPIN (2150 3400) SIG_NAME M_A_CPU0_SA_DQS_DP<0>
J 0
(2160 3410);
DISPLAY 0.659574 (2160 3410);
PAINT MONO (2160 3410);
DISPLAY INVISIBLE (2160 3410);
FORCEPROP 1 LASTPIN (2150 3400) BN 0
J 0
(2138 3408);
DISPLAY 0.680851 (2138 3408);
PAINT GREEN (2138 3408);
FORCEPROP 2 LAST CDS_LIB standard
J 0
(2200 3400);
PAINT MONO (2200 3400);
DISPLAY INVISIBLE (2200 3400);
FORCEPROP 1 LAST BODY_TYPE PLUMBING
J 0
(2200 3450);
DISPLAY 0.872340 (2200 3450);
PAINT GREEN (2200 3450);
DISPLAY INVISIBLE (2200 3450);
FORCEPROP 1 LAST HDL_TAP TRUE
J 0
(2525 3275);
DISPLAY 0.872340 (2525 3275);
DISPLAY INVISIBLE (2525 3275);
FORCEPROP 1 LAST PATH I87
J 0
(2198 3400);
DISPLAY 0.872340 (2198 3400);
PAINT GREEN (2198 3400);
DISPLAY INVISIBLE (2198 3400);
FORCEADD TAP..1
(2200 3600);
FORCEPROP 3 LASTPIN (2150 3600) SIG_NAME M_A_CPU0_SA_DQS_DP<2>
J 0
(2160 3610);
DISPLAY 0.659574 (2160 3610);
PAINT MONO (2160 3610);
DISPLAY INVISIBLE (2160 3610);
FORCEPROP 1 LASTPIN (2150 3600) BN 2
J 0
(2138 3608);
DISPLAY 0.680851 (2138 3608);
PAINT GREEN (2138 3608);
FORCEPROP 2 LAST CDS_LIB standard
J 0
(2200 3600);
DISPLAY INVISIBLE (2200 3600);
FORCEPROP 1 LAST BODY_TYPE PLUMBING
J 0
(2200 3650);
DISPLAY 0.872340 (2200 3650);
PAINT GREEN (2200 3650);
DISPLAY INVISIBLE (2200 3650);
FORCEPROP 1 LAST HDL_TAP TRUE
J 0
(2525 3475);
DISPLAY 0.872340 (2525 3475);
DISPLAY INVISIBLE (2525 3475);
FORCEPROP 1 LAST PATH I88
J 0
(2198 3600);
DISPLAY 0.872340 (2198 3600);
PAINT GREEN (2198 3600);
DISPLAY INVISIBLE (2198 3600);
FORCEADD TAP..1
(2200 3500);
FORCEPROP 3 LASTPIN (2150 3500) SIG_NAME M_A_CPU0_SA_DQS_DP<1>
J 0
(2160 3510);
DISPLAY 0.659574 (2160 3510);
PAINT MONO (2160 3510);
DISPLAY INVISIBLE (2160 3510);
FORCEPROP 1 LASTPIN (2150 3500) BN 1
J 0
(2138 3508);
DISPLAY 0.680851 (2138 3508);
PAINT GREEN (2138 3508);
FORCEPROP 2 LAST CDS_LIB standard
J 0
(2200 3500);
DISPLAY INVISIBLE (2200 3500);
FORCEPROP 1 LAST BODY_TYPE PLUMBING
J 0
(2200 3550);
DISPLAY 0.872340 (2200 3550);
PAINT GREEN (2200 3550);
DISPLAY INVISIBLE (2200 3550);
FORCEPROP 1 LAST HDL_TAP TRUE
J 0
(2525 3375);
DISPLAY 0.872340 (2525 3375);
DISPLAY INVISIBLE (2525 3375);
FORCEPROP 1 LAST PATH I89
J 0
(2198 3500);
DISPLAY 0.872340 (2198 3500);
PAINT GREEN (2198 3500);
DISPLAY INVISIBLE (2198 3500);
FORCEADD TAP..1
(-650 4050);
FORCEPROP 3 LASTPIN (-700 4050) SIG_NAME M_A_CPU0_SA_DQ<26>
J 0
(-690 4060);
DISPLAY 0.659574 (-690 4060);
PAINT MONO (-690 4060);
DISPLAY INVISIBLE (-690 4060);
FORCEPROP 1 LASTPIN (-700 4050) BN 26
J 0
(-712 4058);
DISPLAY 0.680851 (-712 4058);
PAINT GREEN (-712 4058);
FORCEPROP 2 LAST CDS_LIB standard
J 0
(-650 4050);
DISPLAY INVISIBLE (-650 4050);
FORCEPROP 1 LAST BODY_TYPE PLUMBING
J 0
(-650 4100);
DISPLAY 0.872340 (-650 4100);
PAINT GREEN (-650 4100);
DISPLAY INVISIBLE (-650 4100);
FORCEPROP 1 LAST HDL_TAP TRUE
J 0
(-325 3925);
DISPLAY 0.872340 (-325 3925);
DISPLAY INVISIBLE (-325 3925);
FORCEPROP 1 LAST PATH I9
J 0
(-652 4050);
DISPLAY 0.872340 (-652 4050);
PAINT GREEN (-652 4050);
DISPLAY INVISIBLE (-652 4050);
FORCEADD TAP..1
(2375 3750);
FORCEPROP 3 LASTPIN (2325 3750) SIG_NAME M_A_CPU0_SA_DQS_DN<4>
J 0
(2335 3760);
DISPLAY 0.659574 (2335 3760);
PAINT MONO (2335 3760);
DISPLAY INVISIBLE (2335 3760);
FORCEPROP 1 LASTPIN (2325 3750) BN 4
J 0
(2313 3758);
DISPLAY 0.680851 (2313 3758);
PAINT GREEN (2313 3758);
FORCEPROP 2 LAST CDS_LIB standard
J 0
(2375 3750);
PAINT MONO (2375 3750);
DISPLAY INVISIBLE (2375 3750);
FORCEPROP 1 LAST BODY_TYPE PLUMBING
J 0
(2375 3800);
DISPLAY 0.872340 (2375 3800);
PAINT GREEN (2375 3800);
DISPLAY INVISIBLE (2375 3800);
FORCEPROP 1 LAST HDL_TAP TRUE
J 0
(2700 3625);
DISPLAY 0.872340 (2700 3625);
DISPLAY INVISIBLE (2700 3625);
FORCEPROP 1 LAST PATH I90
J 0
(2373 3750);
DISPLAY 0.872340 (2373 3750);
PAINT GREEN (2373 3750);
DISPLAY INVISIBLE (2373 3750);
FORCEADD TAP..1
(2375 3950);
FORCEPROP 3 LASTPIN (2325 3950) SIG_NAME M_A_CPU0_SA_DQS_DN<6>
J 0
(2335 3960);
DISPLAY 0.659574 (2335 3960);
PAINT MONO (2335 3960);
DISPLAY INVISIBLE (2335 3960);
FORCEPROP 1 LASTPIN (2325 3950) BN 6
J 0
(2313 3958);
DISPLAY 0.680851 (2313 3958);
PAINT GREEN (2313 3958);
FORCEPROP 2 LAST CDS_LIB standard
J 0
(2375 3950);
DISPLAY INVISIBLE (2375 3950);
FORCEPROP 1 LAST BODY_TYPE PLUMBING
J 0
(2375 4000);
DISPLAY 0.872340 (2375 4000);
PAINT GREEN (2375 4000);
DISPLAY INVISIBLE (2375 4000);
FORCEPROP 1 LAST HDL_TAP TRUE
J 0
(2700 3825);
DISPLAY 0.872340 (2700 3825);
DISPLAY INVISIBLE (2700 3825);
FORCEPROP 1 LAST PATH I91
J 0
(2373 3950);
DISPLAY 0.872340 (2373 3950);
PAINT GREEN (2373 3950);
DISPLAY INVISIBLE (2373 3950);
FORCEADD TAP..1
(2375 4050);
FORCEPROP 3 LASTPIN (2325 4050) SIG_NAME M_A_CPU0_SA_DQS_DN<7>
J 0
(2335 4060);
DISPLAY 0.659574 (2335 4060);
PAINT MONO (2335 4060);
DISPLAY INVISIBLE (2335 4060);
FORCEPROP 1 LASTPIN (2325 4050) BN 7
J 0
(2313 4058);
DISPLAY 0.680851 (2313 4058);
PAINT GREEN (2313 4058);
FORCEPROP 2 LAST CDS_LIB standard
J 0
(2375 4050);
DISPLAY INVISIBLE (2375 4050);
FORCEPROP 1 LAST BODY_TYPE PLUMBING
J 0
(2375 4100);
DISPLAY 0.872340 (2375 4100);
PAINT GREEN (2375 4100);
DISPLAY INVISIBLE (2375 4100);
FORCEPROP 1 LAST HDL_TAP TRUE
J 0
(2700 3925);
DISPLAY 0.872340 (2700 3925);
DISPLAY INVISIBLE (2700 3925);
FORCEPROP 1 LAST PATH I92
J 0
(2373 4050);
DISPLAY 0.872340 (2373 4050);
PAINT GREEN (2373 4050);
DISPLAY INVISIBLE (2373 4050);
FORCEADD TAP..1
(2375 4150);
FORCEPROP 3 LASTPIN (2325 4150) SIG_NAME M_A_CPU0_SA_DQS_DN<8>
J 0
(2335 4160);
DISPLAY 0.659574 (2335 4160);
PAINT MONO (2335 4160);
DISPLAY INVISIBLE (2335 4160);
FORCEPROP 1 LASTPIN (2325 4150) BN 8
J 0
(2313 4158);
DISPLAY 0.680851 (2313 4158);
PAINT GREEN (2313 4158);
FORCEPROP 2 LAST CDS_LIB standard
J 0
(2375 4150);
DISPLAY INVISIBLE (2375 4150);
FORCEPROP 1 LAST BODY_TYPE PLUMBING
J 0
(2375 4200);
DISPLAY 0.872340 (2375 4200);
PAINT GREEN (2375 4200);
DISPLAY INVISIBLE (2375 4200);
FORCEPROP 1 LAST HDL_TAP TRUE
J 0
(2700 4025);
DISPLAY 0.872340 (2700 4025);
DISPLAY INVISIBLE (2700 4025);
FORCEPROP 1 LAST PATH I93
J 0
(2373 4150);
DISPLAY 0.872340 (2373 4150);
PAINT GREEN (2373 4150);
DISPLAY INVISIBLE (2373 4150);
FORCEADD TAP..1
(2375 4250);
FORCEPROP 3 LASTPIN (2325 4250) SIG_NAME M_A_CPU0_SA_DQS_DN<9>
J 0
(2335 4260);
DISPLAY 0.659574 (2335 4260);
PAINT MONO (2335 4260);
DISPLAY INVISIBLE (2335 4260);
FORCEPROP 1 LASTPIN (2325 4250) BN 9
J 0
(2313 4258);
DISPLAY 0.680851 (2313 4258);
PAINT GREEN (2313 4258);
FORCEPROP 2 LAST CDS_LIB standard
J 0
(2375 4250);
DISPLAY INVISIBLE (2375 4250);
FORCEPROP 1 LAST BODY_TYPE PLUMBING
J 0
(2375 4300);
DISPLAY 0.872340 (2375 4300);
PAINT GREEN (2375 4300);
DISPLAY INVISIBLE (2375 4300);
FORCEPROP 1 LAST HDL_TAP TRUE
J 0
(2700 4125);
DISPLAY 0.872340 (2700 4125);
DISPLAY INVISIBLE (2700 4125);
FORCEPROP 1 LAST PATH I94
J 0
(2373 4250);
DISPLAY 0.872340 (2373 4250);
PAINT GREEN (2373 4250);
DISPLAY INVISIBLE (2373 4250);
FORCEADD TAP..1
(2375 3850);
FORCEPROP 3 LASTPIN (2325 3850) SIG_NAME M_A_CPU0_SA_DQS_DN<5>
J 0
(2335 3860);
DISPLAY 0.659574 (2335 3860);
PAINT MONO (2335 3860);
DISPLAY INVISIBLE (2335 3860);
FORCEPROP 1 LASTPIN (2325 3850) BN 5
J 0
(2313 3858);
DISPLAY 0.680851 (2313 3858);
PAINT GREEN (2313 3858);
FORCEPROP 2 LAST CDS_LIB standard
J 0
(2375 3850);
DISPLAY INVISIBLE (2375 3850);
FORCEPROP 1 LAST BODY_TYPE PLUMBING
J 0
(2375 3900);
DISPLAY 0.872340 (2375 3900);
PAINT GREEN (2375 3900);
DISPLAY INVISIBLE (2375 3900);
FORCEPROP 1 LAST HDL_TAP TRUE
J 0
(2700 3725);
DISPLAY 0.872340 (2700 3725);
DISPLAY INVISIBLE (2700 3725);
FORCEPROP 1 LAST PATH I95
J 0
(2373 3850);
DISPLAY 0.872340 (2373 3850);
PAINT GREEN (2373 3850);
DISPLAY INVISIBLE (2373 3850);
FORCEADD TAP..1
(2375 3550);
FORCEPROP 3 LASTPIN (2325 3550) SIG_NAME M_A_CPU0_SA_DQS_DN<2>
J 0
(2335 3560);
DISPLAY 0.659574 (2335 3560);
PAINT MONO (2335 3560);
DISPLAY INVISIBLE (2335 3560);
FORCEPROP 1 LASTPIN (2325 3550) BN 2
J 0
(2313 3558);
DISPLAY 0.680851 (2313 3558);
PAINT GREEN (2313 3558);
FORCEPROP 2 LAST CDS_LIB standard
J 0
(2375 3550);
DISPLAY INVISIBLE (2375 3550);
FORCEPROP 1 LAST BODY_TYPE PLUMBING
J 0
(2375 3600);
DISPLAY 0.872340 (2375 3600);
PAINT GREEN (2375 3600);
DISPLAY INVISIBLE (2375 3600);
FORCEPROP 1 LAST HDL_TAP TRUE
J 0
(2700 3425);
DISPLAY 0.872340 (2700 3425);
DISPLAY INVISIBLE (2700 3425);
FORCEPROP 1 LAST PATH I96
J 0
(2373 3550);
DISPLAY 0.872340 (2373 3550);
PAINT GREEN (2373 3550);
DISPLAY INVISIBLE (2373 3550);
FORCEADD TAP..1
(2375 3650);
FORCEPROP 3 LASTPIN (2325 3650) SIG_NAME M_A_CPU0_SA_DQS_DN<3>
J 0
(2335 3660);
DISPLAY 0.659574 (2335 3660);
PAINT MONO (2335 3660);
DISPLAY INVISIBLE (2335 3660);
FORCEPROP 1 LASTPIN (2325 3650) BN 3
J 0
(2313 3658);
DISPLAY 0.680851 (2313 3658);
PAINT GREEN (2313 3658);
FORCEPROP 2 LAST CDS_LIB standard
J 0
(2375 3650);
PAINT MONO (2375 3650);
DISPLAY INVISIBLE (2375 3650);
FORCEPROP 1 LAST BODY_TYPE PLUMBING
J 0
(2375 3700);
DISPLAY 0.872340 (2375 3700);
PAINT GREEN (2375 3700);
DISPLAY INVISIBLE (2375 3700);
FORCEPROP 1 LAST HDL_TAP TRUE
J 0
(2700 3525);
DISPLAY 0.872340 (2700 3525);
DISPLAY INVISIBLE (2700 3525);
FORCEPROP 1 LAST PATH I97
J 0
(2373 3650);
DISPLAY 0.872340 (2373 3650);
PAINT GREEN (2373 3650);
DISPLAY INVISIBLE (2373 3650);
FORCEADD TAP..1
(2375 3350);
FORCEPROP 3 LASTPIN (2325 3350) SIG_NAME M_A_CPU0_SA_DQS_DN<0>
J 0
(2335 3360);
DISPLAY 0.659574 (2335 3360);
PAINT MONO (2335 3360);
DISPLAY INVISIBLE (2335 3360);
FORCEPROP 1 LASTPIN (2325 3350) BN 0
J 0
(2313 3358);
DISPLAY 0.680851 (2313 3358);
PAINT GREEN (2313 3358);
FORCEPROP 2 LAST CDS_LIB standard
J 0
(2375 3350);
PAINT MONO (2375 3350);
DISPLAY INVISIBLE (2375 3350);
FORCEPROP 1 LAST BODY_TYPE PLUMBING
J 0
(2375 3400);
DISPLAY 0.872340 (2375 3400);
PAINT GREEN (2375 3400);
DISPLAY INVISIBLE (2375 3400);
FORCEPROP 1 LAST HDL_TAP TRUE
J 0
(2700 3225);
DISPLAY 0.872340 (2700 3225);
DISPLAY INVISIBLE (2700 3225);
FORCEPROP 1 LAST PATH I98
J 0
(2373 3350);
DISPLAY 0.872340 (2373 3350);
PAINT GREEN (2373 3350);
DISPLAY INVISIBLE (2373 3350);
FORCEADD TAP..1
(2375 3450);
FORCEPROP 3 LASTPIN (2325 3450) SIG_NAME M_A_CPU0_SA_DQS_DN<1>
J 0
(2335 3460);
DISPLAY 0.659574 (2335 3460);
PAINT MONO (2335 3460);
DISPLAY INVISIBLE (2335 3460);
FORCEPROP 1 LASTPIN (2325 3450) BN 1
J 0
(2313 3458);
DISPLAY 0.680851 (2313 3458);
PAINT GREEN (2313 3458);
FORCEPROP 2 LAST CDS_LIB standard
J 0
(2375 3450);
DISPLAY INVISIBLE (2375 3450);
FORCEPROP 1 LAST BODY_TYPE PLUMBING
J 0
(2375 3500);
DISPLAY 0.872340 (2375 3500);
PAINT GREEN (2375 3500);
DISPLAY INVISIBLE (2375 3500);
FORCEPROP 1 LAST HDL_TAP TRUE
J 0
(2700 3325);
DISPLAY 0.872340 (2700 3325);
DISPLAY INVISIBLE (2700 3325);
FORCEPROP 1 LAST PATH I99
J 0
(2373 3450);
DISPLAY 0.872340 (2373 3450);
PAINT GREEN (2373 3450);
DISPLAY INVISIBLE (2373 3450);
FORCEADD CAD_NOTE..1
(1200 -150);
FORCEPROP 0 LAST S1 PLACE THE BYPASS CAPS CLOSE TO DIMM
J 0
(1075 -275);
DISPLAY 1.021277 (1075 -275);
PAINT WHITE (1075 -275);
FORCEPROP 2 LAST CDS_LIB logical_power
J 0
(1200 -150);
PAINT MONO (1200 -150);
DISPLAY INVISIBLE (1200 -150);
FORCEPROP 1 LAST COMMENT_BODY TRUE
J 0
(1225 -50);
DISPLAY 0.978723 (1225 -50);
DISPLAY INVISIBLE (1225 -50);
FORCEADD BOM_NOTE..1
(-1775 -500);
FORCEPROP 0 LAST S1 BOM NOTE: 2ND SOURCE IS DFHST8FS385 (@BLUE)
J 0
(-1925 -650);
DISPLAY 0.808511 (-1925 -650);
PAINT SKYBLUE (-1925 -650);
FORCEPROP 2 LAST CDS_LIB logical_power
J 0
(-1775 -500);
DISPLAY INVISIBLE (-1775 -500);
FORCEPROP 1 LAST COMMENT_BODY TRUE
J 0
(-1750 -400);
DISPLAY 0.978723 (-1750 -400);
DISPLAY INVISIBLE (-1750 -400);
FORCEADD QUANTA_TITLE_BLOCK_C..1
(5525 -1450);
FORCEPROP 0 LAST CDS_CON_LAST_MODIFIED Fri Aug 25 14:01:00 2023
J 0
(3640 -1435);
PAINT MONO (3640 -1435);
DISPLAY INVISIBLE (3640 -1435);
FORCEPROP 2 LAST CUSTOM_TXT_CDS <XR_PAGE_TITLE>
J 0
(-2365 3800);
DISPLAY 0.638298 (-2365 3800);
PAINT PINK (-2365 3800);
DISPLAY INVISIBLE (-2365 3800);
FORCEPROP 2 LAST CUSTOM_TXT_CDS <CON_LAST_MODIFIED>
J 0
(3640 -1435);
DISPLAY 0.978723 (3640 -1435);
FORCEPROP 2 LAST CUSTOM_TXT_CDS <CON_PAGE_NUM> OF <CON_TOTAL_PAGES>
J 0
(5079 -1432);
DISPLAY 0.978723 (5079 -1432);
FORCEPROP 2 LAST CUSTOM_TXT_CDS <Q_REV>
J 0
(5341 -1347);
DISPLAY 1.212766 (5341 -1347);
FORCEPROP 2 LAST CUSTOM_TXT_CDS <NAME_1>
J 0
(2350 -1275);
FORCEPROP 2 LAST CUSTOM_TXT_CDS <NAME_2>
J 0
(2350 -1400);
FORCEPROP 2 LAST CUSTOM_TXT_CDS <Q_NUMBER>
J 0
(4122 -1347);
DISPLAY 1.212766 (4122 -1347);
FORCEPROP 2 LAST CUSTOM_TXT_CDS <Q_PROJ>
J 0
(3143 -1348);
DISPLAY 1.212766 (3143 -1348);
FORCEPROP 1 LAST Q_TITLE DDR5 - CPU0 CHA DIMM1(YELLOW)
J 0
(-3841 -1424);
DISPLAY 2.446809 (-3841 -1424);
PAINT GREEN (-3841 -1424);
FORCEPROP 1 LAST Q_DEPT 
J 1
(1762 -1401);
DISPLAY 1.957447 (1762 -1401);
PAINT GREEN (1762 -1401);
FORCEPROP 1 LAST COMMENT_BODY TRUE
J 0
(5537 -1463);
DISPLAY 0.978723 (5537 -1463);
PAINT GREEN (5537 -1463);
DISPLAY INVISIBLE (5537 -1463);
FORCEPROP 2 LAST CDS_XR_PAGE_TITLE CR-82 : @S9S_MB_2U_LIB.S9S_MB_2U(SCH_1):PAGE82
J 0
(-2365 3800);
DISPLAY 0.638298 (-2365 3800);
PAINT PINK (-2365 3800);
DISPLAY INVISIBLE (-2365 3800);
FORCEPROP 2 LAST PAGE_BORDER TRUE
J 0
(-2365 3800);
DISPLAY 0.638298 (-2365 3800);
PAINT PINK (-2365 3800);
DISPLAY INVISIBLE (-2365 3800);
FORCEPROP 1 LAST CDS_LMAN_SYM_OUTLINE -9475,6775,100,-125
J 0
(5525 -1450);
DISPLAY 0.468085 (5525 -1450);
PAINT GREEN (5525 -1450);
DISPLAY INVISIBLE (5525 -1450);
FORCEPROP 2 LAST CDS_LIB pure_quanta
J 0
(5525 -1450);
PAINT MONO (5525 -1450);
DISPLAY INVISIBLE (5525 -1450);
WIRE 17 -1 (-2350 2175)(-2350 2225);
WIRE 17 -1 (-2350 2125)(-2350 2175);
WIRE 17 -1 (-2350 2225)(-2350 2275);
WIRE 17 -1 (-2350 2275)(-2350 2325);
WIRE 17 -1 (-2350 2325)(-2350 2375);
WIRE 17 -1 (-2350 2375)(-2350 2425);
WIRE 17 -1 (-2350 2425)(-2350 2475);
WIRE 17 -1 (-3175 2475)(-2350 2475);
FORCEPROP 2 LAST SIG_NAME M_A_CPU0_SB_CB<7:0>
J 0
(-3085 2485);
DISPLAY 0.680851 (-3085 2485);
PAINT WHITE (-3085 2485);
WIRE 17 -1 (-2350 2575)(-2350 2625);
WIRE 17 -1 (-2350 2625)(-2350 2675);
WIRE 17 -1 (-2350 2675)(-2350 2725);
WIRE 17 -1 (-2350 2725)(-2350 2775);
WIRE 17 -1 (-2350 2775)(-2350 2825);
WIRE 17 -1 (-2350 2825)(-2350 2875);
WIRE 17 -1 (-2350 2875)(-2350 2925);
WIRE 17 -1 (-3175 2925)(-2350 2925);
FORCEPROP 2 LAST SIG_NAME M_A_CPU0_SA_CB<7:0>
J 0
(-3085 2935);
DISPLAY 0.680851 (-3085 2935);
PAINT WHITE (-3085 2935);
WIRE 17 -1 (-2350 3675)(-2350 3725);
WIRE 17 -1 (-2350 3625)(-2350 3675);
WIRE 17 -1 (-2350 3725)(-2350 3775);
WIRE 17 -1 (-2350 3775)(-2350 3825);
WIRE 17 -1 (-2350 3825)(-2350 3875);
WIRE 17 -1 (-2350 3875)(-2350 3925);
WIRE 17 -1 (-3175 3925)(-2350 3925);
FORCEPROP 2 LAST SIG_NAME M_A_CPU0_SB_CA<6:0>
J 0
(-3085 3935);
DISPLAY 0.680851 (-3085 3935);
PAINT WHITE (-3085 3935);
WIRE 17 -1 (-2350 4075)(-2350 4125);
WIRE 17 -1 (-2350 4025)(-2350 4075);
WIRE 17 -1 (-2350 4125)(-2350 4175);
WIRE 17 -1 (-2350 4175)(-2350 4225);
WIRE 17 -1 (-2350 4225)(-2350 4275);
WIRE 17 -1 (-2350 4275)(-2350 4325);
WIRE 17 -1 (-3175 4325)(-2350 4325);
FORCEPROP 2 LAST SIG_NAME M_A_CPU0_SA_CA<6:0>
J 0
(-3085 4335);
DISPLAY 0.680851 (-3085 4335);
PAINT WHITE (-3085 4335);
WIRE 17 -1 (-600 1125)(-600 1175);
WIRE 17 -1 (-600 1175)(-600 1225);
WIRE 17 -1 (-600 1225)(-600 1275);
WIRE 17 -1 (-600 1275)(-600 1325);
WIRE 17 -1 (-600 1325)(-600 1375);
WIRE 17 -1 (-600 1375)(-600 1425);
WIRE 17 -1 (-600 1425)(-600 1475);
WIRE 17 -1 (-600 1475)(-600 1525);
WIRE 17 -1 (-600 1525)(-600 1575);
WIRE 17 -1 (-600 1575)(-600 1625);
WIRE 17 -1 (-600 1625)(-600 1675);
WIRE 17 -1 (-600 1675)(-600 1725);
WIRE 17 -1 (-600 1725)(-600 1775);
WIRE 17 -1 (-600 1775)(-600 1825);
WIRE 17 -1 (-600 1825)(-600 1875);
WIRE 17 -1 (-600 1875)(-600 1925);
WIRE 17 -1 (-600 1925)(-600 1975);
WIRE 17 -1 (-600 1975)(-600 2025);
WIRE 17 -1 (-600 2025)(-600 2075);
WIRE 17 -1 (-600 2075)(-600 2125);
WIRE 17 -1 (-600 2125)(-600 2175);
WIRE 17 -1 (-600 2175)(-600 2225);
WIRE 17 -1 (-600 2225)(-600 2275);
WIRE 17 -1 (-600 2275)(-600 2325);
WIRE 17 -1 (-600 2325)(-600 2375);
WIRE 17 -1 (-600 2375)(-600 2425);
WIRE 17 -1 (-600 2425)(-600 2475);
WIRE 17 -1 (-600 2475)(-600 2525);
WIRE 17 -1 (-600 2525)(-600 2575);
WIRE 17 -1 (-600 2575)(-600 2625);
WIRE 17 -1 (-600 2625)(-600 2675);
WIRE 17 -1 (-600 2675)(125 2675);
FORCEPROP 2 LAST SIG_NAME M_A_CPU0_SB_DQ<31:0>
J 0
(-535 2685);
DISPLAY 0.680851 (-535 2685);
PAINT WHITE (-535 2685);
WIRE 17 -1 (-600 2775)(-600 2825);
WIRE 17 -1 (-600 2825)(-600 2875);
WIRE 17 -1 (-600 2875)(-600 2925);
WIRE 17 -1 (-600 2925)(-600 2975);
WIRE 17 -1 (-600 2975)(-600 3025);
WIRE 17 -1 (-600 3025)(-600 3075);
WIRE 17 -1 (-600 3075)(-600 3125);
WIRE 17 -1 (-600 3125)(-600 3175);
WIRE 17 -1 (-600 3175)(-600 3225);
WIRE 17 -1 (-600 3225)(-600 3275);
WIRE 17 -1 (-600 3275)(-600 3325);
WIRE 17 -1 (-600 3325)(-600 3375);
WIRE 17 -1 (-600 3375)(-600 3425);
WIRE 17 -1 (-600 3425)(-600 3475);
WIRE 17 -1 (-600 3475)(-600 3525);
WIRE 17 -1 (-600 3525)(-600 3575);
WIRE 17 -1 (-600 3575)(-600 3625);
WIRE 17 -1 (-600 3625)(-600 3675);
WIRE 17 -1 (-600 3675)(-600 3725);
WIRE 17 -1 (-600 3725)(-600 3775);
WIRE 17 -1 (-600 3775)(-600 3825);
WIRE 17 -1 (-600 3825)(-600 3875);
WIRE 17 -1 (-600 3875)(-600 3925);
WIRE 17 -1 (-600 3925)(-600 3975);
WIRE 17 -1 (-600 3975)(-600 4025);
WIRE 17 -1 (-600 4025)(-600 4075);
WIRE 17 -1 (-600 4075)(-600 4125);
WIRE 17 -1 (-600 4125)(-600 4175);
WIRE 17 -1 (-600 4175)(-600 4225);
WIRE 17 -1 (-600 4225)(-600 4275);
WIRE 17 -1 (-600 4275)(-600 4325);
WIRE 17 -1 (-600 4325)(125 4325);
FORCEPROP 2 LAST SIG_NAME M_A_CPU0_SA_DQ<31:0>
J 0
(-535 4335);
DISPLAY 0.680851 (-535 4335);
PAINT WHITE (-535 4335);
WIRE 17 -1 (2425 2325)(2425 2425);
WIRE 17 -1 (2425 2425)(2425 2525);
WIRE 17 -1 (2425 2525)(2425 2625);
WIRE 17 -1 (2425 2725)(2425 2625);
WIRE 17 -1 (2425 2725)(2425 2825);
WIRE 17 -1 (2425 2825)(2425 2925);
WIRE 17 -1 (2425 2925)(2425 3025);
WIRE 17 -1 (2425 3025)(2425 3125);
WIRE 17 -1 (2425 3125)(2425 3225);
WIRE 17 -1 (2425 3225)(3275 3225);
FORCEPROP 2 LAST SIG_NAME M_A_CPU0_SB_DQS_DN<9:0>
J 0
(2490 3235);
DISPLAY 0.680851 (2490 3235);
PAINT WHITE (2490 3235);
WIRE 17 -1 (2250 2375)(2250 2475);
WIRE 17 -1 (2250 2475)(2250 2575);
WIRE 17 -1 (2250 2575)(2250 2675);
WIRE 17 -1 (2250 2775)(2250 2675);
WIRE 17 -1 (2250 2775)(2250 2875);
WIRE 17 -1 (2250 2875)(2250 2975);
WIRE 17 -1 (2250 2975)(2250 3075);
WIRE 17 -1 (2250 3075)(2250 3175);
WIRE 17 -1 (2250 3175)(2250 3275);
WIRE 17 -1 (2250 3275)(3275 3275);
FORCEPROP 2 LAST SIG_NAME M_A_CPU0_SB_DQS_DP<9:0>
J 0
(2490 3285);
DISPLAY 0.680851 (2490 3285);
PAINT WHITE (2490 3285);
WIRE 17 -1 (2250 3425)(2250 3525);
WIRE 17 -1 (2250 3525)(2250 3625);
WIRE 17 -1 (2250 3625)(2250 3725);
WIRE 17 -1 (2250 3825)(2250 3725);
WIRE 17 -1 (2250 3825)(2250 3925);
WIRE 17 -1 (2250 3925)(2250 4025);
WIRE 17 -1 (2250 4025)(2250 4125);
WIRE 17 -1 (2250 4125)(2250 4225);
WIRE 17 -1 (2250 4225)(2250 4325);
WIRE 17 -1 (2250 4325)(3275 4325);
FORCEPROP 2 LAST SIG_NAME M_A_CPU0_SA_DQS_DP<9:0>
J 0
(2490 4335);
DISPLAY 0.680851 (2490 4335);
PAINT WHITE (2490 4335);
WIRE 17 -1 (2425 3375)(2425 3475);
WIRE 17 -1 (2425 3475)(2425 3575);
WIRE 17 -1 (2425 3575)(2425 3675);
WIRE 17 -1 (2425 3775)(2425 3675);
WIRE 17 -1 (2425 3775)(2425 3875);
WIRE 17 -1 (2425 3875)(2425 3975);
WIRE 17 -1 (2425 3975)(2425 4075);
WIRE 17 -1 (2425 4075)(2425 4175);
WIRE 17 -1 (2425 4175)(2425 4275);
WIRE 17 -1 (2425 4275)(3275 4275);
FORCEPROP 2 LAST SIG_NAME M_A_CPU0_SA_DQS_DN<9:0>
J 0
(2490 4285);
DISPLAY 0.680851 (2490 4285);
PAINT WHITE (2490 4285);
WIRE 16 -1 (3775 4800)(3775 4300);
WIRE 16 -1 (2075 700)(2075 650);
WIRE 16 -1 (1075 525)(1075 700);
WIRE 16 -1 (-3125 2125)(-3125 1850);
WIRE 16 -1 (5475 950)(5475 650);
WIRE 16 -1 (5475 1000)(5475 950);
WIRE 16 -1 (5225 950)(5475 950);
WIRE 16 -1 (3775 650)(3775 1050);
WIRE 16 -1 (-2075 -25)(-2075 50);
WIRE 16 -1 (1075 325)(1075 100);
WIRE 16 -1 (2700 100)(2700 175);
WIRE 16 -1 (-2425 2000)(-2075 2000);
WIRE 16 -1 (-2425 2050)(-2425 2000);
WIRE 16 -1 (-2425 2050)(-3150 2050);
FORCEPROP 2 LAST SIG_NAME RST_M_AB_CPU0_FPGA_N
J 0
(-3062 2059);
DISPLAY 0.680851 (-3062 2059);
PAINT WHITE (-3062 2059);
WIRE 16 -1 (-2075 1950)(-3150 1950);
FORCEPROP 2 LAST SIG_NAME M_A_CPU0_ALERT_N
J 0
(-3062 1959);
DISPLAY 0.680851 (-3062 1959);
PAINT WHITE (-3062 1959);
WIRE 16 -1 (-3125 1850)(-2075 1850);
WIRE 16 -1 (-2075 1750)(-3075 1750);
FORCEPROP 2 LAST SIG_NAME I3C_SPD_DDRABCD_CPU0_LVC1_SDA
J 0
(-3085 1760);
DISPLAY 0.680851 (-3085 1760);
PAINT WHITE (-3085 1760);
WIRE 16 -1 (-3675 1625)(-3375 1625);
WIRE 16 -1 (-3675 1700)(-3675 1625);
WIRE 16 -1 (-2075 1700)(-3675 1700);
FORCEPROP 2 LAST SIG_NAME I3C_SPD_DDRABCD_CPU0_LVC1_SCL_R1
J 0
(-3135 1710);
DISPLAY 0.680851 (-3135 1710);
PAINT WHITE (-3135 1710);
WIRE 16 -1 (-2025 1550)(-2075 1550);
WIRE 16 -1 (-3175 1625)(-2025 1625);
FORCEPROP 2 LAST SIG_NAME I3C_SPD_DDRABCD_CPU0_LVC1_SCL
J 0
(-2960 1635);
DISPLAY 0.680851 (-2960 1635);
PAINT WHITE (-2960 1635);
WIRE 16 -1 (-2025 1625)(-2025 1550);
WIRE 16 -1 (-2075 1450)(-3175 1450);
FORCEPROP 2 LAST SIG_NAME PWRGD_CHA_CPU0_DIMM1
J 0
(-3087 1459);
DISPLAY 0.680851 (-3087 1459);
PAINT WHITE (-3087 1459);
WIRE 16 -1 (5225 4300)(5475 4300);
WIRE 16 -1 (5225 4250)(5475 4250);
WIRE 16 -1 (5475 4300)(5475 4250);
WIRE 16 -1 (5225 4200)(5475 4200);
WIRE 16 -1 (5475 4250)(5475 4200);
WIRE 16 -1 (5225 4150)(5475 4150);
WIRE 16 -1 (5475 4200)(5475 4150);
WIRE 16 -1 (5225 4100)(5475 4100);
WIRE 16 -1 (5475 4150)(5475 4100);
WIRE 16 -1 (5225 4050)(5475 4050);
WIRE 16 -1 (5475 4100)(5475 4050);
WIRE 16 -1 (5225 4000)(5475 4000);
WIRE 16 -1 (5475 4050)(5475 4000);
WIRE 16 -1 (5225 3950)(5475 3950);
WIRE 16 -1 (5475 4000)(5475 3950);
WIRE 16 -1 (5225 3900)(5475 3900);
WIRE 16 -1 (5475 3950)(5475 3900);
WIRE 16 -1 (5225 3850)(5475 3850);
WIRE 16 -1 (5475 3900)(5475 3850);
WIRE 16 -1 (5225 3800)(5475 3800);
WIRE 16 -1 (5475 3850)(5475 3800);
WIRE 16 -1 (5225 3750)(5475 3750);
WIRE 16 -1 (5475 3800)(5475 3750);
WIRE 16 -1 (5225 3700)(5475 3700);
WIRE 16 -1 (5475 3750)(5475 3700);
WIRE 16 -1 (5225 3650)(5475 3650);
WIRE 16 -1 (5475 3700)(5475 3650);
WIRE 16 -1 (5225 3600)(5475 3600);
WIRE 16 -1 (5475 3650)(5475 3600);
WIRE 16 -1 (5225 3550)(5475 3550);
WIRE 16 -1 (5475 3550)(5475 3600);
WIRE 16 -1 (5225 3500)(5475 3500);
WIRE 16 -1 (5475 3550)(5475 3500);
WIRE 16 -1 (5475 3450)(5225 3450);
WIRE 16 -1 (5475 3500)(5475 3450);
WIRE 16 -1 (5475 3400)(5225 3400);
WIRE 16 -1 (5475 3450)(5475 3400);
WIRE 16 -1 (5225 3350)(5475 3350);
WIRE 16 -1 (5475 3400)(5475 3350);
WIRE 16 -1 (5225 3300)(5475 3300);
WIRE 16 -1 (5475 3350)(5475 3300);
WIRE 16 -1 (5225 3250)(5475 3250);
WIRE 16 -1 (5475 3300)(5475 3250);
WIRE 16 -1 (5225 3200)(5475 3200);
WIRE 16 -1 (5475 3250)(5475 3200);
WIRE 16 -1 (5225 3150)(5475 3150);
WIRE 16 -1 (5475 3200)(5475 3150);
WIRE 16 -1 (5225 3100)(5475 3100);
WIRE 16 -1 (5475 3150)(5475 3100);
WIRE 16 -1 (5225 3050)(5475 3050);
WIRE 16 -1 (5475 3050)(5475 3100);
WIRE 16 -1 (5225 3000)(5475 3000);
WIRE 16 -1 (5475 3050)(5475 3000);
WIRE 16 -1 (5475 2950)(5225 2950);
WIRE 16 -1 (5475 3000)(5475 2950);
WIRE 16 -1 (5475 2900)(5225 2900);
WIRE 16 -1 (5475 2950)(5475 2900);
WIRE 16 -1 (5225 2850)(5475 2850);
WIRE 16 -1 (5475 2900)(5475 2850);
WIRE 16 -1 (5225 2800)(5475 2800);
WIRE 16 -1 (5475 2850)(5475 2800);
WIRE 16 -1 (5225 2750)(5475 2750);
WIRE 16 -1 (5475 2800)(5475 2750);
WIRE 16 -1 (5225 2700)(5475 2700);
WIRE 16 -1 (5475 2750)(5475 2700);
WIRE 16 -1 (5225 2650)(5475 2650);
WIRE 16 -1 (5475 2700)(5475 2650);
WIRE 16 -1 (5225 2600)(5475 2600);
WIRE 16 -1 (5475 2650)(5475 2600);
WIRE 16 -1 (5225 2550)(5475 2550);
WIRE 16 -1 (5475 2550)(5475 2600);
WIRE 16 -1 (5225 2500)(5475 2500);
WIRE 16 -1 (5475 2550)(5475 2500);
WIRE 16 -1 (5475 2450)(5225 2450);
WIRE 16 -1 (5475 2500)(5475 2450);
WIRE 16 -1 (5475 2400)(5225 2400);
WIRE 16 -1 (5475 2450)(5475 2400);
WIRE 16 -1 (5225 2350)(5475 2350);
WIRE 16 -1 (5475 2400)(5475 2350);
WIRE 16 -1 (5225 2300)(5475 2300);
WIRE 16 -1 (5475 2350)(5475 2300);
WIRE 16 -1 (5225 2250)(5475 2250);
WIRE 16 -1 (5475 2300)(5475 2250);
WIRE 16 -1 (5225 2200)(5475 2200);
WIRE 16 -1 (5475 2250)(5475 2200);
WIRE 16 -1 (5225 2150)(5475 2150);
WIRE 16 -1 (5475 2200)(5475 2150);
WIRE 16 -1 (5225 2100)(5475 2100);
WIRE 16 -1 (5475 2150)(5475 2100);
WIRE 16 -1 (5225 2050)(5475 2050);
WIRE 16 -1 (5475 2050)(5475 2100);
WIRE 16 -1 (5225 2000)(5475 2000);
WIRE 16 -1 (5475 2050)(5475 2000);
WIRE 16 -1 (5475 1950)(5225 1950);
WIRE 16 -1 (5475 2000)(5475 1950);
WIRE 16 -1 (5475 1900)(5225 1900);
WIRE 16 -1 (5475 1950)(5475 1900);
WIRE 16 -1 (5475 1850)(5225 1850);
WIRE 16 -1 (5475 1900)(5475 1850);
WIRE 16 -1 (5475 1800)(5225 1800);
WIRE 16 -1 (5475 1850)(5475 1800);
WIRE 16 -1 (5225 1750)(5475 1750);
WIRE 16 -1 (5475 1750)(5475 1800);
WIRE 16 -1 (5475 1700)(5225 1700);
WIRE 16 -1 (5475 1700)(5475 1750);
WIRE 16 -1 (5475 1650)(5225 1650);
WIRE 16 -1 (5475 1700)(5475 1650);
WIRE 16 -1 (5475 1600)(5225 1600);
WIRE 16 -1 (5475 1650)(5475 1600);
WIRE 16 -1 (5225 1550)(5475 1550);
WIRE 16 -1 (5475 1600)(5475 1550);
WIRE 16 -1 (5225 1500)(5475 1500);
WIRE 16 -1 (5475 1550)(5475 1500);
WIRE 16 -1 (5225 1450)(5475 1450);
WIRE 16 -1 (5475 1500)(5475 1450);
WIRE 16 -1 (5225 1400)(5475 1400);
WIRE 16 -1 (5475 1450)(5475 1400);
WIRE 16 -1 (5225 1350)(5475 1350);
WIRE 16 -1 (5475 1400)(5475 1350);
WIRE 16 -1 (5225 1300)(5475 1300);
WIRE 16 -1 (5475 1350)(5475 1300);
WIRE 16 -1 (5225 1250)(5475 1250);
WIRE 16 -1 (5475 1300)(5475 1250);
WIRE 16 -1 (5225 1200)(5475 1200);
WIRE 16 -1 (5475 1200)(5475 1250);
WIRE 16 -1 (5225 1150)(5475 1150);
WIRE 16 -1 (5475 1200)(5475 1150);
WIRE 16 -1 (5225 1050)(5475 1050);
WIRE 16 -1 (5475 1150)(5475 1050);
WIRE 16 -1 (5475 1050)(5475 1000);
WIRE 16 -1 (5225 1000)(5475 1000);
WIRE 16 -1 (4025 4150)(3775 4150);
WIRE 16 -1 (3775 4100)(3775 4150);
WIRE 16 -1 (3775 4100)(4025 4100);
WIRE 16 -1 (4025 4050)(3775 4050);
WIRE 16 -1 (3775 4050)(3775 4100);
WIRE 16 -1 (3775 4000)(3775 4050);
WIRE 16 -1 (3775 4000)(4025 4000);
WIRE 16 -1 (3775 3950)(3775 4000);
WIRE 16 -1 (3775 3950)(4025 3950);
WIRE 16 -1 (3775 3900)(3775 3950);
WIRE 16 -1 (3775 3900)(4025 3900);
WIRE 16 -1 (3775 3850)(3775 3900);
WIRE 16 -1 (3775 3850)(4025 3850);
WIRE 16 -1 (3775 3800)(3775 3850);
WIRE 16 -1 (3775 3800)(4025 3800);
WIRE 16 -1 (3775 3750)(3775 3800);
WIRE 16 -1 (3775 3750)(4025 3750);
WIRE 16 -1 (3775 3700)(3775 3750);
WIRE 16 -1 (3775 3700)(4025 3700);
WIRE 16 -1 (3775 3650)(3775 3700);
WIRE 16 -1 (3775 3650)(4025 3650);
WIRE 16 -1 (3775 3600)(3775 3650);
WIRE 16 -1 (3775 3600)(4025 3600);
WIRE 16 -1 (4025 3550)(3775 3550);
WIRE 16 -1 (3775 3550)(3775 3600);
WIRE 16 -1 (3775 3500)(3775 3550);
WIRE 16 -1 (3775 3500)(4025 3500);
WIRE 16 -1 (3775 3450)(3775 3500);
WIRE 16 -1 (3775 3450)(4025 3450);
WIRE 16 -1 (3775 3400)(3775 3450);
WIRE 16 -1 (3775 3400)(4025 3400);
WIRE 16 -1 (3775 3350)(3775 3400);
WIRE 16 -1 (3775 3350)(4025 3350);
WIRE 16 -1 (3775 3300)(3775 3350);
WIRE 16 -1 (3775 3300)(4025 3300);
WIRE 16 -1 (3775 3250)(3775 3300);
WIRE 16 -1 (3775 3250)(4025 3250);
WIRE 16 -1 (3775 3200)(3775 3250);
WIRE 16 -1 (3775 3200)(4025 3200);
WIRE 16 -1 (3775 3150)(3775 3200);
WIRE 16 -1 (3775 3150)(4025 3150);
WIRE 16 -1 (3775 3100)(3775 3150);
WIRE 16 -1 (3775 3100)(4025 3100);
WIRE 16 -1 (4025 3050)(3775 3050);
WIRE 16 -1 (3775 3050)(3775 3100);
WIRE 16 -1 (3775 3000)(3775 3050);
WIRE 16 -1 (3775 3000)(4025 3000);
WIRE 16 -1 (3775 2950)(3775 3000);
WIRE 16 -1 (3775 2950)(4025 2950);
WIRE 16 -1 (3775 2900)(3775 2950);
WIRE 16 -1 (3775 2900)(4025 2900);
WIRE 16 -1 (3775 2850)(3775 2900);
WIRE 16 -1 (3775 2850)(4025 2850);
WIRE 16 -1 (3775 2800)(3775 2850);
WIRE 16 -1 (3775 2800)(4025 2800);
WIRE 16 -1 (3775 2750)(3775 2800);
WIRE 16 -1 (3775 2750)(4025 2750);
WIRE 16 -1 (3775 2700)(3775 2750);
WIRE 16 -1 (3775 2700)(4025 2700);
WIRE 16 -1 (3775 2650)(3775 2700);
WIRE 16 -1 (3775 2650)(4025 2650);
WIRE 16 -1 (3775 2600)(3775 2650);
WIRE 16 -1 (3775 2600)(4025 2600);
WIRE 16 -1 (4025 2550)(3775 2550);
WIRE 16 -1 (3775 2550)(3775 2600);
WIRE 16 -1 (3775 2500)(3775 2550);
WIRE 16 -1 (3775 2500)(4025 2500);
WIRE 16 -1 (3775 2450)(3775 2500);
WIRE 16 -1 (3775 2450)(4025 2450);
WIRE 16 -1 (3775 2400)(3775 2450);
WIRE 16 -1 (3775 2400)(4025 2400);
WIRE 16 -1 (3775 2350)(3775 2400);
WIRE 16 -1 (3775 2350)(4025 2350);
WIRE 16 -1 (3775 2300)(3775 2350);
WIRE 16 -1 (3775 2300)(4025 2300);
WIRE 16 -1 (3775 2250)(3775 2300);
WIRE 16 -1 (3775 2250)(4025 2250);
WIRE 16 -1 (3775 2200)(3775 2250);
WIRE 16 -1 (3775 2200)(4025 2200);
WIRE 16 -1 (3775 2150)(3775 2200);
WIRE 16 -1 (3775 2150)(4025 2150);
WIRE 16 -1 (3775 2100)(3775 2150);
WIRE 16 -1 (3775 2100)(4025 2100);
WIRE 16 -1 (3775 2050)(3775 2100);
WIRE 16 -1 (4025 2050)(3775 2050);
WIRE 16 -1 (3775 2000)(4025 2000);
WIRE 16 -1 (3775 2000)(3775 2050);
WIRE 16 -1 (3775 1950)(3775 2000);
WIRE 16 -1 (3775 1950)(4025 1950);
WIRE 16 -1 (3775 1900)(3775 1950);
WIRE 16 -1 (3775 1900)(4025 1900);
WIRE 16 -1 (3775 1850)(3775 1900);
WIRE 16 -1 (3775 1850)(4025 1850);
WIRE 16 -1 (3775 1800)(3775 1850);
WIRE 16 -1 (3775 1800)(4025 1800);
WIRE 16 -1 (3775 1750)(3775 1800);
WIRE 16 -1 (3775 1750)(4025 1750);
WIRE 16 -1 (3775 1700)(3775 1750);
WIRE 16 -1 (3775 1700)(4025 1700);
WIRE 16 -1 (3775 1650)(3775 1700);
WIRE 16 -1 (3775 1650)(4025 1650);
WIRE 16 -1 (3775 1600)(3775 1650);
WIRE 16 -1 (3775 1600)(4025 1600);
WIRE 16 -1 (3775 1550)(3775 1600);
WIRE 16 -1 (4025 1550)(3775 1550);
WIRE 16 -1 (3775 1500)(4025 1500);
WIRE 16 -1 (3775 1500)(3775 1550);
WIRE 16 -1 (3775 1450)(3775 1500);
WIRE 16 -1 (3775 1450)(4025 1450);
WIRE 16 -1 (3775 1400)(3775 1450);
WIRE 16 -1 (3775 1400)(4025 1400);
WIRE 16 -1 (3775 1350)(3775 1400);
WIRE 16 -1 (3775 1350)(4025 1350);
WIRE 16 -1 (3775 1300)(3775 1350);
WIRE 16 -1 (3775 1300)(4025 1300);
WIRE 16 -1 (3775 1250)(3775 1300);
WIRE 16 -1 (3775 1250)(4025 1250);
WIRE 16 -1 (3775 1200)(3775 1250);
WIRE 16 -1 (3775 1200)(4025 1200);
WIRE 16 -1 (3775 1150)(3775 1200);
WIRE 16 -1 (3775 1150)(4025 1150);
WIRE 16 -1 (3775 1100)(3775 1150);
WIRE 16 -1 (3775 1100)(4025 1100);
WIRE 16 -1 (3775 1050)(3775 1100);
WIRE 16 -1 (3775 1050)(4025 1050);
WIRE 16 -1 (4025 4200)(3775 4200);
WIRE 16 -1 (3775 4250)(3775 4200);
WIRE 16 -1 (3775 4250)(4025 4250);
WIRE 16 -1 (3775 4300)(3775 4250);
WIRE 16 -1 (4025 4300)(3775 4300);
WIRE 16 -1 (2075 650)(2075 525);
WIRE 16 -1 (2700 650)(2075 650);
WIRE 16 -1 (2700 525)(2700 650);
WIRE 16 -1 (2075 175)(2075 325);
WIRE 16 -1 (2700 175)(2075 175);
WIRE 16 -1 (2700 175)(2700 325);
WIRE 16 -1 (-2075 1800)(-3075 1800);
FORCEPROP 2 LAST SIG_NAME PD_CHA_CPU0_DIMM1_SAA
J 0
(-3085 1810);
DISPLAY 0.680851 (-3085 1810);
PAINT WHITE (-3085 1810);
WIRE 16 -1 (-875 2550)(-700 2550);
WIRE 16 3135 (725 925)(725 -375);
WIRE 16 3135 (3325 925)(725 925);
WIRE 16 3135 (725 -375)(3325 -375);
WIRE 16 3135 (3325 -375)(3325 925);
WIRE 16 -1 (2325 4250)(2050 4250);
WIRE 16 -1 (2325 4150)(2050 4150);
WIRE 16 -1 (2150 4300)(2050 4300);
WIRE 16 -1 (2150 4200)(2050 4200);
WIRE 16 -1 (2150 4100)(2050 4100);
WIRE 16 -1 (2325 4050)(2050 4050);
WIRE 16 -1 (2325 3850)(2050 3850);
WIRE 16 -1 (2325 3950)(2050 3950);
WIRE 16 -1 (2150 4000)(2050 4000);
WIRE 16 -1 (2150 3900)(2050 3900);
WIRE 16 -1 (2325 3750)(2050 3750);
WIRE 16 -1 (2325 3650)(2050 3650);
WIRE 16 -1 (2150 3800)(2050 3800);
WIRE 16 -1 (2150 3600)(2050 3600);
WIRE 16 -1 (2150 3700)(2050 3700);
WIRE 16 -1 (2325 3550)(2050 3550);
WIRE 16 -1 (2050 3450)(2325 3450);
WIRE 16 -1 (2325 3350)(2050 3350);
WIRE 16 -1 (2150 3500)(2050 3500);
WIRE 16 -1 (2150 3400)(2050 3400);
WIRE 16 -1 (2325 3200)(2050 3200);
WIRE 16 -1 (2325 3100)(2050 3100);
WIRE 16 -1 (2150 3250)(2050 3250);
WIRE 16 -1 (2150 3150)(2050 3150);
WIRE 16 -1 (2325 2900)(2050 2900);
WIRE 16 -1 (2325 3000)(2050 3000);
WIRE 16 -1 (2150 3050)(2050 3050);
WIRE 16 -1 (2150 2950)(2050 2950);
WIRE 16 -1 (2150 2850)(2050 2850);
WIRE 16 -1 (2325 2800)(2050 2800);
WIRE 16 -1 (2325 2700)(2050 2700);
WIRE 16 -1 (2325 2600)(2050 2600);
WIRE 16 -1 (2150 2750)(2050 2750);
WIRE 16 -1 (2150 2650)(2050 2650);
WIRE 16 -1 (2325 2500)(2050 2500);
WIRE 16 -1 (2325 2400)(2050 2400);
WIRE 16 -1 (2150 2550)(2050 2550);
WIRE 16 -1 (2150 2450)(2050 2450);
WIRE 16 -1 (2150 2350)(2050 2350);
WIRE 16 -1 (2325 2300)(2050 2300);
WIRE 16 -1 (-875 4300)(-700 4300);
WIRE 16 -1 (-875 4250)(-700 4250);
WIRE 16 -1 (-875 4150)(-700 4150);
WIRE 16 -1 (-875 4100)(-700 4100);
WIRE 16 -1 (-875 4200)(-700 4200);
WIRE 16 -1 (-2250 4250)(-2075 4250);
WIRE 16 -1 (-2250 4300)(-2075 4300);
WIRE 16 -1 (-2250 4200)(-2075 4200);
WIRE 16 -1 (-2250 4150)(-2075 4150);
WIRE 16 -1 (-2250 4100)(-2075 4100);
WIRE 16 -1 (-875 4050)(-700 4050);
WIRE 16 -1 (-875 4000)(-700 4000);
WIRE 16 -1 (-875 3950)(-700 3950);
WIRE 16 -1 (-875 3900)(-700 3900);
WIRE 16 -1 (-875 3850)(-700 3850);
WIRE 16 -1 (-875 3800)(-700 3800);
WIRE 16 -1 (-875 3750)(-700 3750);
WIRE 16 -1 (-875 3600)(-700 3600);
WIRE 16 -1 (-875 3650)(-700 3650);
WIRE 16 -1 (-875 3700)(-700 3700);
WIRE 16 -1 (-875 3500)(-700 3500);
WIRE 16 -1 (-875 3550)(-700 3550);
WIRE 16 -1 (-875 3350)(-700 3350);
WIRE 16 -1 (-875 3450)(-700 3450);
WIRE 16 -1 (-875 3400)(-700 3400);
WIRE 16 -1 (-875 3250)(-700 3250);
WIRE 16 -1 (-875 3300)(-700 3300);
WIRE 16 -1 (-875 3200)(-700 3200);
WIRE 16 -1 (-875 3100)(-700 3100);
WIRE 16 -1 (-875 3150)(-700 3150);
WIRE 16 -1 (-875 3050)(-700 3050);
WIRE 16 -1 (-875 3000)(-700 3000);
WIRE 16 -1 (-875 2950)(-700 2950);
WIRE 16 -1 (-875 2900)(-700 2900);
WIRE 16 -1 (-875 2850)(-700 2850);
WIRE 16 -1 (-875 2800)(-700 2800);
WIRE 16 -1 (-875 2750)(-700 2750);
WIRE 16 -1 (-875 2600)(-700 2600);
WIRE 16 -1 (-875 2650)(-700 2650);
WIRE 16 -1 (-875 2500)(-700 2500);
WIRE 16 -1 (-875 2450)(-700 2450);
WIRE 16 -1 (-875 2400)(-700 2400);
WIRE 16 -1 (-875 2350)(-700 2350);
WIRE 16 -1 (-875 2200)(-700 2200);
WIRE 16 -1 (-875 2300)(-700 2300);
WIRE 16 -1 (-875 2250)(-700 2250);
WIRE 16 -1 (-875 2100)(-700 2100);
WIRE 16 -1 (-875 2150)(-700 2150);
WIRE 16 -1 (-875 2050)(-700 2050);
WIRE 16 -1 (-875 2000)(-700 2000);
WIRE 16 -1 (-875 1950)(-700 1950);
WIRE 16 -1 (-875 1900)(-700 1900);
WIRE 16 -1 (-875 1850)(-700 1850);
WIRE 16 -1 (-875 1800)(-700 1800);
WIRE 16 -1 (-875 1750)(-700 1750);
WIRE 16 -1 (-875 1700)(-700 1700);
WIRE 16 -1 (-875 1650)(-700 1650);
WIRE 16 -1 (-875 1600)(-700 1600);
WIRE 16 -1 (-875 1550)(-700 1550);
WIRE 16 -1 (-875 1500)(-700 1500);
WIRE 16 -1 (-875 1450)(-700 1450);
WIRE 16 -1 (-875 1300)(-700 1300);
WIRE 16 -1 (-875 1350)(-700 1350);
WIRE 16 -1 (-875 1400)(-700 1400);
WIRE 16 -1 (-875 1200)(-700 1200);
WIRE 16 -1 (-875 1250)(-700 1250);
WIRE 16 -1 (-875 1150)(-700 1150);
WIRE 16 -1 (-875 1100)(-700 1100);
WIRE 16 -1 (-2250 4000)(-2075 4000);
WIRE 16 -1 (-2250 4050)(-2075 4050);
WIRE 16 -1 (-2250 3850)(-2075 3850);
WIRE 16 -1 (-2250 3900)(-2075 3900);
WIRE 16 -1 (-2250 3750)(-2075 3750);
WIRE 16 -1 (-2250 3800)(-2075 3800);
WIRE 16 -1 (-2250 3600)(-2075 3600);
WIRE 16 -1 (-2250 3650)(-2075 3650);
WIRE 16 -1 (-2250 3700)(-2075 3700);
WIRE 16 -1 (-2250 2850)(-2075 2850);
WIRE 16 -1 (-2250 2900)(-2075 2900);
WIRE 16 -1 (-2250 2800)(-2075 2800);
WIRE 16 -1 (-2250 2750)(-2075 2750);
WIRE 16 -1 (-2250 2700)(-2075 2700);
WIRE 16 -1 (-2250 2650)(-2075 2650);
WIRE 16 -1 (-2250 2600)(-2075 2600);
WIRE 16 -1 (-2250 2550)(-2075 2550);
WIRE 16 -1 (-2250 2450)(-2075 2450);
WIRE 16 -1 (-2250 2350)(-2075 2350);
WIRE 16 -1 (-2250 2400)(-2075 2400);
WIRE 16 -1 (-2250 2300)(-2075 2300);
WIRE 16 -1 (-2250 2250)(-2075 2250);
WIRE 16 -1 (-2250 2200)(-2075 2200);
WIRE 16 -1 (-2250 2100)(-2075 2100);
WIRE 16 -1 (-2250 2150)(-2075 2150);
WIRE 16 -1 (-2075 3500)(-3175 3500);
FORCEPROP 2 LAST SIG_NAME M_A_CPU0_SA_PAR
J 0
(-3087 3509);
DISPLAY 0.680851 (-3087 3509);
PAINT WHITE (-3087 3509);
WIRE 16 -1 (-2075 3450)(-3175 3450);
FORCEPROP 2 LAST SIG_NAME M_A_CPU0_SB_PAR
J 0
(-3087 3459);
DISPLAY 0.680851 (-3087 3459);
PAINT WHITE (-3087 3459);
WIRE 16 -1 (-2075 3350)(-3175 3350);
FORCEPROP 2 LAST SIG_NAME M_A_CPU0_SA_CS_N<1>
J 0
(-3087 3359);
DISPLAY 0.680851 (-3087 3359);
PAINT WHITE (-3087 3359);
WIRE 16 -1 (-2075 3200)(-3175 3200);
FORCEPROP 2 LAST SIG_NAME M_A_CPU0_SB_CS_N<1>
J 0
(-3087 3209);
DISPLAY 0.680851 (-3087 3209);
PAINT WHITE (-3087 3209);
WIRE 16 -1 (-2075 3150)(-3175 3150);
FORCEPROP 2 LAST SIG_NAME M_A_CPU0_SB_CS_N<0>
J 0
(-3087 3159);
DISPLAY 0.680851 (-3087 3159);
PAINT WHITE (-3087 3159);
WIRE 16 -1 (-2075 3300)(-3175 3300);
FORCEPROP 2 LAST SIG_NAME M_A_CPU0_SA_CS_N<0>
J 0
(-3087 3309);
DISPLAY 0.680851 (-3087 3309);
PAINT WHITE (-3087 3309);
WIRE 16 -1 (-2075 3050)(-3175 3050);
FORCEPROP 2 LAST SIG_NAME M_A_CPU0_CLK_DP<0>
J 0
(-3087 3059);
DISPLAY 0.680851 (-3087 3059);
PAINT WHITE (-3087 3059);
WIRE 16 -1 (-2075 3000)(-3175 3000);
FORCEPROP 2 LAST SIG_NAME M_A_CPU0_CLK_DN<0>
J 0
(-3087 3009);
DISPLAY 0.680851 (-3087 3009);
PAINT WHITE (-3087 3009);
WIRE 16 -1 (-2075 900)(-3175 900);
FORCEPROP 2 LAST SIG_NAME M_A_CPU0_SA_RSP<0>
J 0
(-3087 909);
DISPLAY 0.680851 (-3087 909);
PAINT WHITE (-3087 909);
WIRE 16 -1 (-2075 850)(-3175 850);
FORCEPROP 2 LAST SIG_NAME M_A_CPU0_SB_RSP<0>
J 0
(-3087 859);
DISPLAY 0.680851 (-3087 859);
PAINT WHITE (-3087 859);
WIRE 16 -1 (-2075 1350)(-3175 1350);
FORCEPROP 2 LAST SIG_NAME TP_CHA_CPU0_DIMM1_FRU_6
J 0
(-3087 1359);
DISPLAY 0.680851 (-3087 1359);
PAINT WHITE (-3087 1359);
WIRE 16 -1 (-2075 1300)(-3175 1300);
FORCEPROP 2 LAST SIG_NAME TP_CHA_CPU0_DIMM1_FRU_5
J 0
(-3087 1309);
DISPLAY 0.680851 (-3087 1309);
PAINT WHITE (-3087 1309);
WIRE 16 -1 (-2075 1250)(-3175 1250);
FORCEPROP 2 LAST SIG_NAME TP_CHA_CPU0_DIMM1_FRU_4
J 0
(-3087 1259);
DISPLAY 0.680851 (-3087 1259);
PAINT WHITE (-3087 1259);
WIRE 16 -1 (-2075 1200)(-3175 1200);
FORCEPROP 2 LAST SIG_NAME TP_CHA_CPU0_DIMM1_FRU_3
J 0
(-3087 1209);
DISPLAY 0.680851 (-3087 1209);
PAINT WHITE (-3087 1209);
WIRE 16 -1 (-2075 1150)(-3175 1150);
FORCEPROP 2 LAST SIG_NAME TP_CHA_CPU0_DIMM1_FRU_2
J 0
(-3087 1159);
DISPLAY 0.680851 (-3087 1159);
PAINT WHITE (-3087 1159);
WIRE 16 -1 (-2075 1100)(-3175 1100);
FORCEPROP 2 LAST SIG_NAME TP_CHA_CPU0_DIMM1_FRU_1
J 0
(-3087 1109);
DISPLAY 0.680851 (-3087 1109);
PAINT WHITE (-3087 1109);
WIRE 16 -1 (-2075 1050)(-3175 1050);
FORCEPROP 2 LAST SIG_NAME TP_CHA_CPU0_DIMM1_FRU_0
J 0
(-3087 1059);
DISPLAY 0.680851 (-3087 1059);
PAINT WHITE (-3087 1059);
WIRE 16 -1 (-2075 350)(-3175 350);
FORCEPROP 2 LAST SIG_NAME PD_CHA_CPU0_DIMM1_SAA
J 0
(-3087 359);
DISPLAY 0.680851 (-3087 359);
PAINT WHITE (-3087 359);
WIRE 16 -1 (-2075 250)(-2075 350);
DOT 1 (3775 2650);
DOT 1 (3775 2350);
DOT 1 (3775 2300);
DOT 1 (5475 3250);
DOT 1 (3775 3250);
DOT 1 (3775 3200);
DOT 1 (3775 3750);
DOT 1 (5475 3700);
DOT 1 (3775 3350);
DOT 1 (3775 2200);
DOT 1 (5475 4050);
DOT 1 (5475 3800);
DOT 1 (3775 1250);
DOT 1 (3775 1200);
DOT 1 (3775 1100);
DOT 1 (3775 1050);
DOT 1 (3775 1150);
DOT 1 (3775 1400);
DOT 1 (3775 1450);
DOT 1 (3775 1300);
DOT 1 (3775 1350);
DOT 1 (3775 1500);
DOT 1 (3775 1650);
DOT 1 (3775 1700);
DOT 1 (3775 1600);
DOT 1 (3775 1550);
DOT 1 (3775 1750);
DOT 1 (3775 1800);
DOT 1 (3775 1900);
DOT 1 (3775 1950);
DOT 1 (3775 1850);
DOT 1 (3775 2000);
DOT 1 (3775 2150);
DOT 1 (3775 2100);
DOT 1 (3775 2500);
DOT 1 (3775 2450);
DOT 1 (3775 2400);
DOT 1 (3775 2550);
DOT 1 (3775 2750);
DOT 1 (3775 2700);
DOT 1 (3775 2600);
DOT 1 (3775 2800);
DOT 1 (3775 3050);
DOT 1 (3775 2900);
DOT 1 (3775 2850);
DOT 1 (3775 3000);
DOT 1 (3775 2950);
DOT 1 (3775 3150);
DOT 1 (3775 3100);
DOT 1 (3775 3300);
DOT 1 (3775 3550);
DOT 1 (3775 3500);
DOT 1 (3775 3450);
DOT 1 (3775 3400);
DOT 1 (3775 3800);
DOT 1 (3775 3700);
DOT 1 (3775 3600);
DOT 1 (3775 3650);
DOT 1 (3775 3850);
DOT 1 (3775 4000);
DOT 1 (3775 3950);
DOT 1 (3775 3900);
DOT 1 (3775 4050);
DOT 1 (3775 4100);
DOT 1 (3775 4300);
DOT 1 (3775 4250);
DOT 1 (5475 1000);
DOT 1 (5475 950);
DOT 1 (5475 1250);
DOT 1 (5475 1300);
DOT 1 (5475 1350);
DOT 1 (5475 1400);
DOT 1 (5475 1450);
DOT 1 (5475 1500);
DOT 1 (5475 1600);
DOT 1 (5475 1550);
DOT 1 (5475 1650);
DOT 1 (5475 1700);
DOT 1 (5475 1750);
DOT 1 (5475 1800);
DOT 1 (5475 1900);
DOT 1 (5475 1950);
DOT 1 (5475 2000);
DOT 1 (5475 2050);
DOT 1 (5475 2100);
DOT 1 (5475 2150);
DOT 1 (5475 2200);
DOT 1 (5475 2250);
DOT 1 (5475 2300);
DOT 1 (5475 2350);
DOT 1 (5475 2400);
DOT 1 (5475 2450);
DOT 1 (5475 2500);
DOT 1 (5475 2550);
DOT 1 (5475 2650);
DOT 1 (5475 2600);
DOT 1 (5475 2700);
DOT 1 (5475 2750);
DOT 1 (5475 2800);
DOT 1 (5475 2850);
DOT 1 (5475 2900);
DOT 1 (5475 2950);
DOT 1 (5475 3000);
DOT 1 (5475 3050);
DOT 1 (5475 3100);
DOT 1 (5475 3150);
DOT 1 (5475 3200);
DOT 1 (5475 3300);
DOT 1 (5475 3350);
DOT 1 (5475 3400);
DOT 1 (5475 3450);
DOT 1 (5475 3500);
DOT 1 (5475 3550);
DOT 1 (5475 3600);
DOT 1 (5475 3650);
DOT 1 (5475 3750);
DOT 1 (5475 3850);
DOT 1 (5475 3900);
DOT 1 (5475 3950);
DOT 1 (5475 4000);
DOT 1 (5475 4100);
DOT 1 (5475 4150);
DOT 1 (5475 4200);
DOT 1 (5475 4250);
DOT 1 (5475 1850);
DOT 1 (3775 2050);
DOT 1 (5475 1200);
DOT 1 (5475 1150);
DOT 1 (5475 1050);
DOT 1 (3775 2250);
DOT 1 (2075 650);
DOT 1 (2700 175);
FORCENOTE
20210728 MODIFY FOR GT
(-3625 4925) 0;
DISPLAY LEFT (-3625 4925);
DISPLAY 2.510638 (-3625 4925);
PAINT PINK (-3625 4925);
QUIT
